FILE_TYPE = MACRO_DRAWING;
SET COLOR_WIRE YELLOW;
SET COLOR_PROP MONO;
SET COLOR_DOT WHITE;
SET COLOR_ARC YELLOW;
SET COLOR_BODY GREEN;
SET COLOR_NOTE MONO;
SET PROP_DISPLAY VALUE;
SET PAGE_NUMBER P103;
FORCEADD RES..1
(300 1250);
FORCEPROP 1 LAST VALUE 27.4
J 2
(225 1200);
DISPLAY 0.617021 (225 1200);
PAINT SKYBLUE (225 1200);
FORCEPROP 1 LASTPIN (200 1250) $PN 1
J 0
(212 1262);
DISPLAY 0.617021 (212 1262);
PAINT ORANGE (212 1262);
FORCEPROP 1 LAST WATTAGE 1/16W
J 2
(275 1150);
DISPLAY 0.617021 (275 1150);
PAINT SKYBLUE (275 1150);
FORCEPROP 1 LAST LOCATION R4D25
J 0
(250 1300);
DISPLAY 0.617021 (250 1300);
PAINT AQUA (250 1300);
FORCEPROP 1 LAST TOLERANCE 1%
J 0
(300 1150);
DISPLAY 0.617021 (300 1150);
PAINT SKYBLUE (300 1150);
FORCEPROP 1 LAST PACK_TYPE 0402
J 0
(375 1150);
DISPLAY 0.617021 (375 1150);
PAINT SKYBLUE (375 1150);
FORCEPROP 1 LAST MATERIAL CHIP
J 0
(350 1200);
DISPLAY 0.617021 (350 1200);
PAINT SKYBLUE (350 1200);
FORCEPROP 1 LASTPIN (400 1250) $PN 2
J 0
(362 1262);
DISPLAY 0.617021 (362 1262);
PAINT ORANGE (362 1262);
FORCEPROP 1 LAST PART_NUMBER G21796-182
J 0
(425 1250);
DISPLAY 0.617021 (425 1250);
PAINT BLUE (425 1250);
FORCEPROP 0 LAST ROOM DB1200Z
J 0
(250 1400);
DISPLAY 1.021277 (250 1400);
PAINT ORANGE (250 1400);
DISPLAY INVISIBLE (250 1400);
FORCEPROP 1 LAST PATH I1
J 0
(250 1400);
DISPLAY 0.978723 (250 1400);
PAINT WHITE (250 1400);
DISPLAY INVISIBLE (250 1400);
FORCEPROP 2 LAST CDS_LOCATION R4D25
J 0
(250 1300);
DISPLAY 0.617021 (250 1300);
PAINT AQUA (250 1300);
DISPLAY INVISIBLE (250 1300);
FORCEPROP 2 LAST SEC 1
J 0
(250 1450);
DISPLAY 0.680851 (250 1450);
PAINT MONO (250 1450);
DISPLAY INVISIBLE (250 1450);
FORCEPROP 2 LAST SEC_TYPE 0402
J 0
(250 1450);
DISPLAY 1.021277 (250 1450);
PAINT ORANGE (250 1450);
DISPLAY INVISIBLE (250 1450);
FORCEPROP 2 LAST CDS_LIB mstr_discrete
J 0
(300 1250);
PAINT ORANGE (300 1250);
DISPLAY INVISIBLE (300 1250);
FORCEPROP 0 LAST BOM_COST SYS_CLOCK
J 0
(250 1500);
DISPLAY 1.021277 (250 1500);
PAINT ORANGE (250 1500);
DISPLAY INVISIBLE (250 1500);
FORCEADD OFFPAGE..1
(-4900 4900);
FORCEPROP 2 LAST $XR0 102 
J 0
(-5152 4900);
DISPLAY 0.638298 (-5152 4900);
PAINT MONO (-5152 4900);
FORCEPROP 2 LAST CDS_LIB mstr_standard
J 0
(-4900 4900);
PAINT ORANGE (-4900 4900);
DISPLAY INVISIBLE (-4900 4900);
FORCEPROP 2 LAST PATH I10
J 0
(-4850 4975);
DISPLAY 1.021277 (-4850 4975);
PAINT ORANGE (-4850 4975);
DISPLAY INVISIBLE (-4850 4975);
FORCEPROP 1 LAST COMMENT_BODY TRUE
J 0
(-4775 4800);
DISPLAY 0.872340 (-4775 4800);
PAINT GREEN (-4775 4800);
DISPLAY INVISIBLE (-4775 4800);
FORCEPROP 1 LAST OFFPAGE TRUE
J 0
(-4575 4775);
DISPLAY 0.872340 (-4575 4775);
PAINT GREEN (-4575 4775);
DISPLAY INVISIBLE (-4575 4775);
FORCEADD OFFPAGE..1
(-675 3200);
FORCEPROP 2 LAST $XR0 102 
J 0
(-927 3200);
DISPLAY 0.638298 (-927 3200);
PAINT MONO (-927 3200);
FORCEPROP 2 LAST PATH I100
J 0
(-625 3275);
DISPLAY 1.021277 (-625 3275);
PAINT ORANGE (-625 3275);
DISPLAY INVISIBLE (-625 3275);
FORCEPROP 1 LAST COMMENT_BODY TRUE
J 0
(-550 3100);
DISPLAY 0.872340 (-550 3100);
PAINT GREEN (-550 3100);
DISPLAY INVISIBLE (-550 3100);
FORCEPROP 2 LAST CDS_LIB mstr_standard
J 0
(-675 3200);
PAINT ORANGE (-675 3200);
DISPLAY INVISIBLE (-675 3200);
FORCEPROP 1 LAST OFFPAGE TRUE
J 0
(-350 3075);
DISPLAY 0.872340 (-350 3075);
PAINT GREEN (-350 3075);
DISPLAY INVISIBLE (-350 3075);
FORCEADD OFFPAGE..2
(1950 2875);
FORCEPROP 2 LAST $XR0 21 
J 0
(2139 2875);
DISPLAY 0.638298 (2139 2875);
PAINT MONO (2139 2875);
FORCEPROP 1 LAST COMMENT_BODY TRUE
J 0
(1905 2780);
DISPLAY 0.872340 (1905 2780);
PAINT GREEN (1905 2780);
DISPLAY INVISIBLE (1905 2780);
FORCEPROP 2 LAST CDS_LIB mstr_standard
J 0
(1950 2875);
PAINT ORANGE (1950 2875);
DISPLAY INVISIBLE (1950 2875);
FORCEPROP 2 LAST PATH I102
J 0
(2125 2950);
DISPLAY 1.021277 (2125 2950);
PAINT ORANGE (2125 2950);
DISPLAY INVISIBLE (2125 2950);
FORCEPROP 1 LAST OFFPAGE TRUE
J 0
(2275 2750);
DISPLAY 0.872340 (2275 2750);
PAINT GREEN (2275 2750);
DISPLAY INVISIBLE (2275 2750);
FORCEADD RES..1
(300 2875);
FORCEPROP 1 LASTPIN (200 2875) $PN 1
J 0
(212 2887);
DISPLAY 0.617021 (212 2887);
PAINT ORANGE (212 2887);
FORCEPROP 1 LAST VALUE 27.4
J 2
(225 2825);
DISPLAY 0.617021 (225 2825);
PAINT SKYBLUE (225 2825);
FORCEPROP 1 LAST WATTAGE 1/16W
J 2
(275 2775);
DISPLAY 0.617021 (275 2775);
PAINT SKYBLUE (275 2775);
FORCEPROP 1 LAST LOCATION R4D17
J 0
(250 2925);
DISPLAY 0.617021 (250 2925);
PAINT AQUA (250 2925);
FORCEPROP 1 LAST TOLERANCE 1%
J 0
(300 2775);
DISPLAY 0.617021 (300 2775);
PAINT SKYBLUE (300 2775);
FORCEPROP 1 LAST PACK_TYPE 0402
J 0
(375 2775);
DISPLAY 0.617021 (375 2775);
PAINT SKYBLUE (375 2775);
FORCEPROP 1 LAST MATERIAL CHIP
J 0
(350 2825);
DISPLAY 0.617021 (350 2825);
PAINT SKYBLUE (350 2825);
FORCEPROP 1 LASTPIN (400 2875) $PN 2
J 0
(362 2887);
DISPLAY 0.617021 (362 2887);
PAINT ORANGE (362 2887);
FORCEPROP 1 LAST PART_NUMBER G21796-182
J 0
(425 2875);
DISPLAY 0.617021 (425 2875);
PAINT BLUE (425 2875);
FORCEPROP 0 LAST ROOM DB1200Z
J 0
(250 3025);
DISPLAY 1.021277 (250 3025);
PAINT ORANGE (250 3025);
DISPLAY INVISIBLE (250 3025);
FORCEPROP 1 LAST PATH I104
J 0
(250 3025);
DISPLAY 0.978723 (250 3025);
PAINT WHITE (250 3025);
DISPLAY INVISIBLE (250 3025);
FORCEPROP 2 LAST CDS_LOCATION R4D17
J 0
(250 2925);
DISPLAY 0.617021 (250 2925);
PAINT AQUA (250 2925);
DISPLAY INVISIBLE (250 2925);
FORCEPROP 2 LAST CDS_LIB mstr_discrete
J 0
(300 2875);
PAINT ORANGE (300 2875);
DISPLAY INVISIBLE (300 2875);
FORCEPROP 0 LAST BOM_COST SYS_CLOCK
J 0
(250 3125);
DISPLAY 1.021277 (250 3125);
PAINT ORANGE (250 3125);
DISPLAY INVISIBLE (250 3125);
FORCEPROP 2 LAST SEC_TYPE 0402
J 0
(250 3075);
DISPLAY 1.021277 (250 3075);
PAINT ORANGE (250 3075);
DISPLAY INVISIBLE (250 3075);
FORCEPROP 2 LAST SEC 1
J 0
(250 3075);
DISPLAY 0.680851 (250 3075);
PAINT MONO (250 3075);
DISPLAY INVISIBLE (250 3075);
FORCEADD OFFPAGE..1
(-675 2875);
FORCEPROP 2 LAST $XR0 102 
J 0
(-927 2875);
DISPLAY 0.638298 (-927 2875);
PAINT MONO (-927 2875);
FORCEPROP 2 LAST PATH I105
J 0
(-625 2950);
DISPLAY 1.021277 (-625 2950);
PAINT ORANGE (-625 2950);
DISPLAY INVISIBLE (-625 2950);
FORCEPROP 1 LAST COMMENT_BODY TRUE
J 0
(-550 2775);
DISPLAY 0.872340 (-550 2775);
PAINT GREEN (-550 2775);
DISPLAY INVISIBLE (-550 2775);
FORCEPROP 2 LAST CDS_LIB mstr_standard
J 0
(-675 2875);
PAINT ORANGE (-675 2875);
DISPLAY INVISIBLE (-675 2875);
FORCEPROP 1 LAST OFFPAGE TRUE
J 0
(-350 2750);
DISPLAY 0.872340 (-350 2750);
PAINT GREEN (-350 2750);
DISPLAY INVISIBLE (-350 2750);
FORCEADD OFFPAGE..2
(1950 2550);
FORCEPROP 2 LAST $XR0 21 
J 0
(2139 2550);
DISPLAY 0.638298 (2139 2550);
PAINT MONO (2139 2550);
FORCEPROP 1 LAST COMMENT_BODY TRUE
J 0
(1905 2455);
DISPLAY 0.872340 (1905 2455);
PAINT GREEN (1905 2455);
DISPLAY INVISIBLE (1905 2455);
FORCEPROP 2 LAST CDS_LIB mstr_standard
J 0
(1950 2550);
PAINT ORANGE (1950 2550);
DISPLAY INVISIBLE (1950 2550);
FORCEPROP 1 LAST OFFPAGE TRUE
J 0
(2275 2425);
DISPLAY 0.872340 (2275 2425);
PAINT GREEN (2275 2425);
DISPLAY INVISIBLE (2275 2425);
FORCEPROP 2 LAST PATH I108
J 0
(2125 2625);
DISPLAY 1.021277 (2125 2625);
PAINT ORANGE (2125 2625);
DISPLAY INVISIBLE (2125 2625);
FORCEADD RES..1
(300 2550);
FORCEPROP 1 LAST VALUE 27.4
J 2
(225 2500);
DISPLAY 0.617021 (225 2500);
PAINT SKYBLUE (225 2500);
FORCEPROP 1 LAST WATTAGE 1/16W
J 2
(275 2450);
DISPLAY 0.617021 (275 2450);
PAINT SKYBLUE (275 2450);
FORCEPROP 1 LAST MATERIAL CHIP
J 0
(350 2500);
DISPLAY 0.617021 (350 2500);
PAINT SKYBLUE (350 2500);
FORCEPROP 1 LAST PACK_TYPE 0402
J 0
(375 2450);
DISPLAY 0.617021 (375 2450);
PAINT SKYBLUE (375 2450);
FORCEPROP 1 LAST TOLERANCE 1%
J 0
(300 2450);
DISPLAY 0.617021 (300 2450);
PAINT SKYBLUE (300 2450);
FORCEPROP 1 LASTPIN (200 2550) $PN 1
J 0
(212 2562);
DISPLAY 0.617021 (212 2562);
PAINT ORANGE (212 2562);
FORCEPROP 1 LAST LOCATION R4D14
J 0
(250 2575);
DISPLAY 0.617021 (250 2575);
PAINT AQUA (250 2575);
FORCEPROP 1 LASTPIN (400 2550) $PN 2
J 0
(362 2562);
DISPLAY 0.617021 (362 2562);
PAINT ORANGE (362 2562);
FORCEPROP 1 LAST PART_NUMBER G21796-182
J 0
(425 2550);
DISPLAY 0.617021 (425 2550);
PAINT BLUE (425 2550);
FORCEPROP 2 LAST CDS_LIB mstr_discrete
J 0
(300 2550);
PAINT ORANGE (300 2550);
DISPLAY INVISIBLE (300 2550);
FORCEPROP 1 LAST PATH I109
J 0
(250 2700);
DISPLAY 0.978723 (250 2700);
PAINT WHITE (250 2700);
DISPLAY INVISIBLE (250 2700);
FORCEPROP 2 LAST SEC_TYPE 0402
J 0
(250 2750);
DISPLAY 1.021277 (250 2750);
PAINT ORANGE (250 2750);
DISPLAY INVISIBLE (250 2750);
FORCEPROP 0 LAST ROOM DB1200Z
J 0
(250 2675);
DISPLAY 1.021277 (250 2675);
PAINT ORANGE (250 2675);
DISPLAY INVISIBLE (250 2675);
FORCEPROP 0 LAST BOM_COST SYS_CLOCK
J 0
(250 2775);
DISPLAY 1.021277 (250 2775);
PAINT ORANGE (250 2775);
DISPLAY INVISIBLE (250 2775);
FORCEPROP 2 LAST SEC 1
J 0
(250 2750);
DISPLAY 0.680851 (250 2750);
PAINT MONO (250 2750);
DISPLAY INVISIBLE (250 2750);
FORCEPROP 2 LAST CDS_LOCATION R4D14
J 0
(250 2575);
DISPLAY 0.617021 (250 2575);
PAINT AQUA (250 2575);
DISPLAY INVISIBLE (250 2575);
FORCEADD OFFPAGE..2
(-2225 4525);
FORCEPROP 2 LAST $XR0 70 
J 0
(-2036 4525);
DISPLAY 0.638298 (-2036 4525);
PAINT MONO (-2036 4525);
FORCEPROP 1 LAST COMMENT_BODY TRUE
J 0
(-2270 4430);
DISPLAY 0.872340 (-2270 4430);
PAINT GREEN (-2270 4430);
DISPLAY INVISIBLE (-2270 4430);
FORCEPROP 2 LAST CDS_LIB mstr_standard
J 0
(-2225 4525);
PAINT ORANGE (-2225 4525);
DISPLAY INVISIBLE (-2225 4525);
FORCEPROP 2 LAST PATH I11
J 0
(-2050 4600);
DISPLAY 1.021277 (-2050 4600);
PAINT ORANGE (-2050 4600);
DISPLAY INVISIBLE (-2050 4600);
FORCEPROP 1 LAST OFFPAGE TRUE
J 0
(-1900 4400);
DISPLAY 0.872340 (-1900 4400);
PAINT GREEN (-1900 4400);
DISPLAY INVISIBLE (-1900 4400);
FORCEADD OFFPAGE..1
(-675 2550);
FORCEPROP 2 LAST $XR0 102 
J 0
(-927 2550);
DISPLAY 0.638298 (-927 2550);
PAINT MONO (-927 2550);
FORCEPROP 1 LAST COMMENT_BODY TRUE
J 0
(-550 2450);
DISPLAY 0.872340 (-550 2450);
PAINT GREEN (-550 2450);
DISPLAY INVISIBLE (-550 2450);
FORCEPROP 2 LAST CDS_LIB mstr_standard
J 0
(-675 2550);
PAINT ORANGE (-675 2550);
DISPLAY INVISIBLE (-675 2550);
FORCEPROP 2 LAST PATH I110
J 0
(-625 2625);
DISPLAY 1.021277 (-625 2625);
PAINT ORANGE (-625 2625);
DISPLAY INVISIBLE (-625 2625);
FORCEPROP 1 LAST OFFPAGE TRUE
J 0
(-350 2425);
DISPLAY 0.872340 (-350 2425);
PAINT GREEN (-350 2425);
DISPLAY INVISIBLE (-350 2425);
FORCEADD OFFPAGE..2
(1950 2225);
FORCEPROP 2 LAST $XR0 21 
J 0
(2139 2225);
DISPLAY 0.638298 (2139 2225);
PAINT MONO (2139 2225);
FORCEPROP 1 LAST COMMENT_BODY TRUE
J 0
(1905 2130);
DISPLAY 0.872340 (1905 2130);
PAINT GREEN (1905 2130);
DISPLAY INVISIBLE (1905 2130);
FORCEPROP 2 LAST CDS_LIB mstr_standard
J 0
(1950 2225);
PAINT ORANGE (1950 2225);
DISPLAY INVISIBLE (1950 2225);
FORCEPROP 2 LAST PATH I113
J 0
(2125 2300);
DISPLAY 1.021277 (2125 2300);
PAINT ORANGE (2125 2300);
DISPLAY INVISIBLE (2125 2300);
FORCEPROP 1 LAST OFFPAGE TRUE
J 0
(2275 2100);
DISPLAY 0.872340 (2275 2100);
PAINT GREEN (2275 2100);
DISPLAY INVISIBLE (2275 2100);
FORCEADD RES..1
(300 2225);
FORCEPROP 1 LAST VALUE 27.4
J 2
(225 2175);
DISPLAY 0.617021 (225 2175);
PAINT SKYBLUE (225 2175);
FORCEPROP 1 LASTPIN (200 2225) $PN 1
J 0
(212 2237);
DISPLAY 0.617021 (212 2237);
PAINT ORANGE (212 2237);
FORCEPROP 1 LAST WATTAGE 1/16W
J 2
(275 2125);
DISPLAY 0.617021 (275 2125);
PAINT SKYBLUE (275 2125);
FORCEPROP 1 LAST LOCATION R4D22
J 0
(250 2275);
DISPLAY 0.617021 (250 2275);
PAINT AQUA (250 2275);
FORCEPROP 1 LAST MATERIAL CHIP
J 0
(350 2175);
DISPLAY 0.617021 (350 2175);
PAINT SKYBLUE (350 2175);
FORCEPROP 1 LAST PACK_TYPE 0402
J 0
(375 2125);
DISPLAY 0.617021 (375 2125);
PAINT SKYBLUE (375 2125);
FORCEPROP 1 LAST TOLERANCE 1%
J 0
(300 2125);
DISPLAY 0.617021 (300 2125);
PAINT SKYBLUE (300 2125);
FORCEPROP 1 LASTPIN (400 2225) $PN 2
J 0
(362 2237);
DISPLAY 0.617021 (362 2237);
PAINT ORANGE (362 2237);
FORCEPROP 1 LAST PART_NUMBER G21796-182
J 0
(425 2225);
DISPLAY 0.617021 (425 2225);
PAINT BLUE (425 2225);
FORCEPROP 2 LAST CDS_LOCATION R4D22
J 0
(250 2275);
DISPLAY 0.617021 (250 2275);
PAINT AQUA (250 2275);
DISPLAY INVISIBLE (250 2275);
FORCEPROP 2 LAST SEC_TYPE 0402
J 0
(250 2425);
DISPLAY 1.021277 (250 2425);
PAINT ORANGE (250 2425);
DISPLAY INVISIBLE (250 2425);
FORCEPROP 0 LAST BOM_COST SYS_CLOCK
J 0
(250 2475);
DISPLAY 1.021277 (250 2475);
PAINT ORANGE (250 2475);
DISPLAY INVISIBLE (250 2475);
FORCEPROP 2 LAST SEC 1
J 0
(250 2425);
DISPLAY 0.680851 (250 2425);
PAINT MONO (250 2425);
DISPLAY INVISIBLE (250 2425);
FORCEPROP 1 LAST PATH I114
J 0
(250 2375);
DISPLAY 0.978723 (250 2375);
PAINT WHITE (250 2375);
DISPLAY INVISIBLE (250 2375);
FORCEPROP 0 LAST ROOM DB1200Z
J 0
(250 2375);
DISPLAY 1.021277 (250 2375);
PAINT ORANGE (250 2375);
DISPLAY INVISIBLE (250 2375);
FORCEPROP 2 LAST CDS_LIB mstr_discrete
J 0
(300 2225);
PAINT ORANGE (300 2225);
DISPLAY INVISIBLE (300 2225);
FORCEADD OFFPAGE..1
(-675 2225);
FORCEPROP 2 LAST $XR0 102 
J 0
(-927 2225);
DISPLAY 0.638298 (-927 2225);
PAINT MONO (-927 2225);
FORCEPROP 1 LAST COMMENT_BODY TRUE
J 0
(-550 2125);
DISPLAY 0.872340 (-550 2125);
PAINT GREEN (-550 2125);
DISPLAY INVISIBLE (-550 2125);
FORCEPROP 2 LAST CDS_LIB mstr_standard
J 0
(-675 2225);
PAINT ORANGE (-675 2225);
DISPLAY INVISIBLE (-675 2225);
FORCEPROP 2 LAST PATH I115
J 0
(-625 2300);
DISPLAY 1.021277 (-625 2300);
PAINT ORANGE (-625 2300);
DISPLAY INVISIBLE (-625 2300);
FORCEPROP 1 LAST OFFPAGE TRUE
J 0
(-350 2100);
DISPLAY 0.872340 (-350 2100);
PAINT GREEN (-350 2100);
DISPLAY INVISIBLE (-350 2100);
FORCEADD OFFPAGE..2
(1950 1900);
FORCEPROP 2 LAST $XR0 21 
J 0
(2139 1900);
DISPLAY 0.638298 (2139 1900);
PAINT MONO (2139 1900);
FORCEPROP 2 LAST CDS_LIB mstr_standard
J 0
(1950 1900);
PAINT ORANGE (1950 1900);
DISPLAY INVISIBLE (1950 1900);
FORCEPROP 1 LAST COMMENT_BODY TRUE
J 0
(1905 1805);
DISPLAY 0.872340 (1905 1805);
PAINT GREEN (1905 1805);
DISPLAY INVISIBLE (1905 1805);
FORCEPROP 1 LAST OFFPAGE TRUE
J 0
(2275 1775);
DISPLAY 0.872340 (2275 1775);
PAINT GREEN (2275 1775);
DISPLAY INVISIBLE (2275 1775);
FORCEPROP 2 LAST PATH I118
J 0
(2125 1975);
DISPLAY 1.021277 (2125 1975);
PAINT ORANGE (2125 1975);
DISPLAY INVISIBLE (2125 1975);
FORCEADD RES..1
(300 1900);
FORCEPROP 1 LASTPIN (200 1900) $PN 1
J 0
(212 1912);
DISPLAY 0.617021 (212 1912);
PAINT ORANGE (212 1912);
FORCEPROP 1 LAST VALUE 27.4
J 2
(225 1850);
DISPLAY 0.617021 (225 1850);
PAINT SKYBLUE (225 1850);
FORCEPROP 1 LAST WATTAGE 1/16W
J 2
(275 1800);
DISPLAY 0.617021 (275 1800);
PAINT SKYBLUE (275 1800);
FORCEPROP 1 LAST LOCATION R4D20
J 0
(250 1950);
DISPLAY 0.617021 (250 1950);
PAINT AQUA (250 1950);
FORCEPROP 1 LASTPIN (400 1900) $PN 2
J 0
(362 1912);
DISPLAY 0.617021 (362 1912);
PAINT ORANGE (362 1912);
FORCEPROP 1 LAST MATERIAL CHIP
J 0
(350 1850);
DISPLAY 0.617021 (350 1850);
PAINT SKYBLUE (350 1850);
FORCEPROP 1 LAST PACK_TYPE 0402
J 0
(375 1800);
DISPLAY 0.617021 (375 1800);
PAINT SKYBLUE (375 1800);
FORCEPROP 1 LAST TOLERANCE 1%
J 0
(300 1800);
DISPLAY 0.617021 (300 1800);
PAINT SKYBLUE (300 1800);
FORCEPROP 1 LAST PART_NUMBER G21796-182
J 0
(425 1900);
DISPLAY 0.617021 (425 1900);
PAINT BLUE (425 1900);
FORCEPROP 2 LAST CDS_LOCATION R4D20
J 0
(250 1950);
DISPLAY 0.617021 (250 1950);
PAINT AQUA (250 1950);
DISPLAY INVISIBLE (250 1950);
FORCEPROP 2 LAST CDS_LIB mstr_discrete
J 0
(300 1900);
PAINT ORANGE (300 1900);
DISPLAY INVISIBLE (300 1900);
FORCEPROP 2 LAST SEC_TYPE 0402
J 0
(250 2100);
DISPLAY 1.021277 (250 2100);
PAINT ORANGE (250 2100);
DISPLAY INVISIBLE (250 2100);
FORCEPROP 0 LAST BOM_COST SYS_CLOCK
J 0
(250 2150);
DISPLAY 1.021277 (250 2150);
PAINT ORANGE (250 2150);
DISPLAY INVISIBLE (250 2150);
FORCEPROP 2 LAST SEC 1
J 0
(250 2100);
DISPLAY 0.680851 (250 2100);
PAINT MONO (250 2100);
DISPLAY INVISIBLE (250 2100);
FORCEPROP 1 LAST PATH I119
J 0
(250 2050);
DISPLAY 0.978723 (250 2050);
PAINT WHITE (250 2050);
DISPLAY INVISIBLE (250 2050);
FORCEPROP 0 LAST ROOM DB1200Z
J 0
(250 2050);
DISPLAY 1.021277 (250 2050);
PAINT ORANGE (250 2050);
DISPLAY INVISIBLE (250 2050);
FORCEADD OFFPAGE..1
(-675 1900);
FORCEPROP 2 LAST $XR0 102 
J 0
(-927 1900);
DISPLAY 0.638298 (-927 1900);
PAINT MONO (-927 1900);
FORCEPROP 2 LAST PATH I120
J 0
(-625 1975);
DISPLAY 1.021277 (-625 1975);
PAINT ORANGE (-625 1975);
DISPLAY INVISIBLE (-625 1975);
FORCEPROP 1 LAST COMMENT_BODY TRUE
J 0
(-550 1800);
DISPLAY 0.872340 (-550 1800);
PAINT GREEN (-550 1800);
DISPLAY INVISIBLE (-550 1800);
FORCEPROP 2 LAST CDS_LIB mstr_standard
J 0
(-675 1900);
PAINT ORANGE (-675 1900);
DISPLAY INVISIBLE (-675 1900);
FORCEPROP 1 LAST OFFPAGE TRUE
J 0
(-350 1775);
DISPLAY 0.872340 (-350 1775);
PAINT GREEN (-350 1775);
DISPLAY INVISIBLE (-350 1775);
FORCEADD RES..1
(-3325 4800);
FORCEPROP 1 LAST WATTAGE 1/16W
J 2
(-3350 4650);
DISPLAY 0.617021 (-3350 4650);
PAINT SKYBLUE (-3350 4650);
FORCEPROP 1 LAST VALUE 42.2
J 2
(-3350 4700);
DISPLAY 0.617021 (-3350 4700);
PAINT SKYBLUE (-3350 4700);
FORCEPROP 1 LASTPIN (-3425 4800) $PN 1
J 0
(-3413 4812);
DISPLAY 0.617021 (-3413 4812);
PAINT ORANGE (-3413 4812);
FORCEPROP 1 LAST PART_NUMBER G21796-259
J 0
(-3375 4900);
DISPLAY 0.617021 (-3375 4900);
PAINT BLUE (-3375 4900);
FORCEPROP 1 LAST LOCATION R7P9
J 0
(-3375 4850);
DISPLAY 0.617021 (-3375 4850);
PAINT AQUA (-3375 4850);
FORCEPROP 1 LAST TOLERANCE 1.0%
J 0
(-3325 4700);
DISPLAY 0.617021 (-3325 4700);
PAINT SKYBLUE (-3325 4700);
FORCEPROP 1 LASTPIN (-3225 4800) $PN 2
J 0
(-3263 4812);
DISPLAY 0.617021 (-3263 4812);
PAINT ORANGE (-3263 4812);
FORCEPROP 1 LAST MATERIAL EMPTY
J 0
(-3325 4650);
DISPLAY 0.617021 (-3325 4650);
PAINT RED (-3325 4650);
FORCEPROP 1 LAST PACK_TYPE 0402
J 0
(-3075 4650);
DISPLAY 0.617021 (-3075 4650);
PAINT SKYBLUE (-3075 4650);
FORCEPROP 2 LAST CDS_LOCATION R7P9
J 0
(-3375 4850);
DISPLAY 0.617021 (-3375 4850);
PAINT AQUA (-3375 4850);
DISPLAY INVISIBLE (-3375 4850);
FORCEPROP 0 LAST ROOM DB1200Z
J 0
(-3375 5000);
DISPLAY 1.021277 (-3375 5000);
PAINT ORANGE (-3375 5000);
DISPLAY INVISIBLE (-3375 5000);
FORCEPROP 1 LAST PATH I121
J 0
(-3375 4950);
DISPLAY 0.978723 (-3375 4950);
PAINT WHITE (-3375 4950);
DISPLAY INVISIBLE (-3375 4950);
FORCEPROP 2 LAST SEC 1
J 0
(-3375 5000);
DISPLAY 0.680851 (-3375 5000);
PAINT MONO (-3375 5000);
DISPLAY INVISIBLE (-3375 5000);
FORCEPROP 2 LAST SEC_TYPE 0402
J 0
(-3375 5000);
DISPLAY 1.021277 (-3375 5000);
PAINT ORANGE (-3375 5000);
DISPLAY INVISIBLE (-3375 5000);
FORCEPROP 2 LAST CDS_LIB mstr_discrete
J 0
(-3325 4800);
PAINT MONO (-3325 4800);
DISPLAY INVISIBLE (-3325 4800);
FORCEPROP 0 LAST BOM_COST SYS_CLOCK
J 0
(-3375 5100);
DISPLAY 1.021277 (-3375 5100);
PAINT ORANGE (-3375 5100);
DISPLAY INVISIBLE (-3375 5100);
FORCEADD RES..1
(-3300 4425);
FORCEPROP 1 LASTPIN (-3400 4425) $PN 1
J 0
(-3388 4437);
DISPLAY 0.617021 (-3388 4437);
PAINT ORANGE (-3388 4437);
FORCEPROP 1 LAST WATTAGE 1/16W
J 2
(-3325 4275);
DISPLAY 0.617021 (-3325 4275);
PAINT SKYBLUE (-3325 4275);
FORCEPROP 1 LAST VALUE 42.2
J 2
(-3325 4325);
DISPLAY 0.617021 (-3325 4325);
PAINT SKYBLUE (-3325 4325);
FORCEPROP 1 LAST LOCATION R7P12
J 0
(-3350 4475);
DISPLAY 0.617021 (-3350 4475);
PAINT AQUA (-3350 4475);
FORCEPROP 1 LAST TOLERANCE 1.0%
J 0
(-3300 4325);
DISPLAY 0.617021 (-3300 4325);
PAINT SKYBLUE (-3300 4325);
FORCEPROP 1 LAST MATERIAL EMPTY
J 0
(-3300 4275);
DISPLAY 0.617021 (-3300 4275);
PAINT RED (-3300 4275);
FORCEPROP 1 LASTPIN (-3200 4425) $PN 2
J 0
(-3238 4437);
DISPLAY 0.617021 (-3238 4437);
PAINT ORANGE (-3238 4437);
FORCEPROP 1 LAST PART_NUMBER G21796-259
J 0
(-3350 4525);
DISPLAY 0.617021 (-3350 4525);
PAINT BLUE (-3350 4525);
FORCEPROP 1 LAST PACK_TYPE 0402
J 0
(-3050 4275);
DISPLAY 0.617021 (-3050 4275);
PAINT SKYBLUE (-3050 4275);
FORCEPROP 2 LAST CDS_LOCATION R7P12
J 0
(-3350 4475);
DISPLAY 0.617021 (-3350 4475);
PAINT AQUA (-3350 4475);
DISPLAY INVISIBLE (-3350 4475);
FORCEPROP 2 LAST CDS_LIB mstr_discrete
J 0
(-3300 4425);
PAINT MONO (-3300 4425);
DISPLAY INVISIBLE (-3300 4425);
FORCEPROP 1 LAST PATH I123
J 0
(-3350 4575);
DISPLAY 0.978723 (-3350 4575);
PAINT WHITE (-3350 4575);
DISPLAY INVISIBLE (-3350 4575);
FORCEPROP 0 LAST ROOM DB1200Z
J 0
(-3350 4625);
DISPLAY 1.021277 (-3350 4625);
PAINT ORANGE (-3350 4625);
DISPLAY INVISIBLE (-3350 4625);
FORCEPROP 2 LAST SEC 1
J 0
(-3350 4625);
DISPLAY 0.680851 (-3350 4625);
PAINT MONO (-3350 4625);
DISPLAY INVISIBLE (-3350 4625);
FORCEPROP 2 LAST SEC_TYPE 0402
J 0
(-3350 4625);
DISPLAY 1.021277 (-3350 4625);
PAINT ORANGE (-3350 4625);
DISPLAY INVISIBLE (-3350 4625);
FORCEPROP 0 LAST BOM_COST SYS_CLOCK
J 0
(-3350 4725);
DISPLAY 1.021277 (-3350 4725);
PAINT ORANGE (-3350 4725);
DISPLAY INVISIBLE (-3350 4725);
FORCEADD RES..1
(-3325 4075);
FORCEPROP 1 LAST WATTAGE 1/16W
J 2
(-3350 3925);
DISPLAY 0.617021 (-3350 3925);
PAINT SKYBLUE (-3350 3925);
FORCEPROP 1 LAST VALUE 42.2
J 2
(-3350 3975);
DISPLAY 0.617021 (-3350 3975);
PAINT SKYBLUE (-3350 3975);
FORCEPROP 1 LAST TOLERANCE 1.0%
J 0
(-3325 3975);
DISPLAY 0.617021 (-3325 3975);
PAINT SKYBLUE (-3325 3975);
FORCEPROP 1 LAST MATERIAL EMPTY
J 0
(-3325 3925);
DISPLAY 0.617021 (-3325 3925);
PAINT RED (-3325 3925);
FORCEPROP 1 LAST PACK_TYPE 0402
J 0
(-3075 3925);
DISPLAY 0.617021 (-3075 3925);
PAINT SKYBLUE (-3075 3925);
FORCEPROP 1 LASTPIN (-3425 4075) $PN 1
J 0
(-3413 4087);
DISPLAY 0.617021 (-3413 4087);
PAINT ORANGE (-3413 4087);
FORCEPROP 1 LASTPIN (-3225 4075) $PN 2
J 0
(-3263 4087);
DISPLAY 0.617021 (-3263 4087);
PAINT ORANGE (-3263 4087);
FORCEPROP 1 LAST PART_NUMBER G21796-259
J 0
(-3175 4075);
DISPLAY 0.617021 (-3175 4075);
PAINT BLUE (-3175 4075);
FORCEPROP 1 LAST LOCATION R7P6
J 0
(-3375 4125);
DISPLAY 0.617021 (-3375 4125);
PAINT AQUA (-3375 4125);
FORCEPROP 2 LAST CDS_LIB mstr_discrete
J 0
(-3325 4075);
PAINT MONO (-3325 4075);
DISPLAY INVISIBLE (-3325 4075);
FORCEPROP 2 LAST SEC_TYPE 0402
J 0
(-3375 4275);
DISPLAY 1.021277 (-3375 4275);
PAINT ORANGE (-3375 4275);
DISPLAY INVISIBLE (-3375 4275);
FORCEPROP 2 LAST SEC 1
J 0
(-3375 4275);
DISPLAY 0.680851 (-3375 4275);
PAINT MONO (-3375 4275);
DISPLAY INVISIBLE (-3375 4275);
FORCEPROP 2 LAST CDS_LOCATION R7P6
J 0
(-3375 4125);
DISPLAY 0.617021 (-3375 4125);
PAINT AQUA (-3375 4125);
DISPLAY INVISIBLE (-3375 4125);
FORCEPROP 1 LAST PATH I125
J 0
(-3375 4225);
DISPLAY 0.978723 (-3375 4225);
PAINT WHITE (-3375 4225);
DISPLAY INVISIBLE (-3375 4225);
FORCEPROP 0 LAST ROOM DB1200Z
J 0
(-3375 4275);
DISPLAY 1.021277 (-3375 4275);
PAINT ORANGE (-3375 4275);
DISPLAY INVISIBLE (-3375 4275);
FORCEPROP 0 LAST BOM_COST SYS_CLOCK
J 0
(-3375 4375);
DISPLAY 1.021277 (-3375 4375);
PAINT ORANGE (-3375 4375);
DISPLAY INVISIBLE (-3375 4375);
FORCEADD GND..1
(-2800 3975);
FORCEPROP 3 LASTPIN (-2800 4025) SIG_NAME GND\g
J 0
(-2790 4035);
DISPLAY 0.659574 (-2790 4035);
PAINT MONO (-2790 4035);
DISPLAY INVISIBLE (-2790 4035);
FORCEPROP 1 LAST BODY_TYPE PLUMBING
J 0
(-2845 3932);
DISPLAY 0.340426 (-2845 3932);
PAINT GREEN (-2845 3932);
DISPLAY INVISIBLE (-2845 3932);
FORCEPROP 1 LAST VOLTAGE 0.0V
J 0
(-2845 3932);
DISPLAY 0.340426 (-2845 3932);
PAINT SKYBLUE (-2845 3932);
DISPLAY INVISIBLE (-2845 3932);
FORCEPROP 1 LAST PATH I126
J 0
(-2725 3975);
DISPLAY 0.872340 (-2725 3975);
PAINT AQUA (-2725 3975);
DISPLAY INVISIBLE (-2725 3975);
FORCEPROP 1 LAST SIZE 1B
J 0
(-2725 3925);
DISPLAY 0.872340 (-2725 3925);
PAINT AQUA (-2725 3925);
DISPLAY INVISIBLE (-2725 3925);
FORCEPROP 2 LAST CDS_LIB mstr_symbols
J 0
(-2800 3975);
PAINT MONO (-2800 3975);
DISPLAY INVISIBLE (-2800 3975);
FORCEPROP 1 LAST HDL_POWER GND
J 0
(-2800 4125);
DISPLAY 0.872340 (-2800 4125);
PAINT GREEN (-2800 4125);
DISPLAY INVISIBLE (-2800 4125);
FORCEADD RES..1
(-3325 3750);
FORCEPROP 1 LAST WATTAGE 1/16W
J 2
(-3350 3600);
DISPLAY 0.617021 (-3350 3600);
PAINT SKYBLUE (-3350 3600);
FORCEPROP 1 LAST VALUE 42.2
J 2
(-3350 3650);
DISPLAY 0.617021 (-3350 3650);
PAINT SKYBLUE (-3350 3650);
FORCEPROP 1 LAST LOCATION R7P7
J 0
(-3375 3800);
DISPLAY 0.617021 (-3375 3800);
PAINT AQUA (-3375 3800);
FORCEPROP 1 LAST TOLERANCE 1.0%
J 0
(-3325 3650);
DISPLAY 0.617021 (-3325 3650);
PAINT SKYBLUE (-3325 3650);
FORCEPROP 1 LAST MATERIAL EMPTY
J 0
(-3325 3600);
DISPLAY 0.617021 (-3325 3600);
PAINT RED (-3325 3600);
FORCEPROP 1 LAST PACK_TYPE 0402
J 0
(-3075 3600);
DISPLAY 0.617021 (-3075 3600);
PAINT SKYBLUE (-3075 3600);
FORCEPROP 1 LAST PART_NUMBER G21796-259
J 0
(-3175 3750);
DISPLAY 0.617021 (-3175 3750);
PAINT BLUE (-3175 3750);
FORCEPROP 1 LASTPIN (-3425 3750) $PN 1
J 0
(-3413 3762);
DISPLAY 0.787234 (-3413 3762);
PAINT ORANGE (-3413 3762);
DISPLAY INVISIBLE (-3413 3762);
FORCEPROP 2 LAST CDS_LOCATION R7P7
J 0
(-3375 3800);
DISPLAY 0.617021 (-3375 3800);
PAINT AQUA (-3375 3800);
DISPLAY INVISIBLE (-3375 3800);
FORCEPROP 1 LAST PATH I127
J 0
(-3375 3900);
DISPLAY 0.978723 (-3375 3900);
PAINT WHITE (-3375 3900);
DISPLAY INVISIBLE (-3375 3900);
FORCEPROP 0 LAST ROOM DB1200Z
J 0
(-3375 3950);
DISPLAY 1.021277 (-3375 3950);
PAINT ORANGE (-3375 3950);
DISPLAY INVISIBLE (-3375 3950);
FORCEPROP 2 LAST $SEC 1
J 0
(-3375 3950);
PAINT MONO (-3375 3950);
DISPLAY INVISIBLE (-3375 3950);
FORCEPROP 2 LAST CDS_SEC 1
J 0
(-3375 3950);
PAINT MONO (-3375 3950);
DISPLAY INVISIBLE (-3375 3950);
FORCEPROP 0 LAST BOM_COST SYS_CLOCK
J 0
(-3375 4050);
DISPLAY 1.021277 (-3375 4050);
PAINT ORANGE (-3375 4050);
DISPLAY INVISIBLE (-3375 4050);
FORCEPROP 2 LAST CDS_LIB mstr_discrete
J 0
(-3325 3750);
PAINT MONO (-3325 3750);
DISPLAY INVISIBLE (-3325 3750);
FORCEPROP 1 LASTPIN (-3225 3750) $PN 2
J 0
(-3263 3762);
DISPLAY 0.787234 (-3263 3762);
PAINT ORANGE (-3263 3762);
DISPLAY INVISIBLE (-3263 3762);
FORCEADD GND..1
(-2800 3650);
FORCEPROP 3 LASTPIN (-2800 3700) SIG_NAME GND\g
J 0
(-2790 3710);
DISPLAY 0.659574 (-2790 3710);
PAINT MONO (-2790 3710);
DISPLAY INVISIBLE (-2790 3710);
FORCEPROP 1 LAST VOLTAGE 0.0V
J 0
(-2845 3607);
DISPLAY 0.340426 (-2845 3607);
PAINT SKYBLUE (-2845 3607);
DISPLAY INVISIBLE (-2845 3607);
FORCEPROP 1 LAST BODY_TYPE PLUMBING
J 0
(-2845 3607);
DISPLAY 0.340426 (-2845 3607);
PAINT GREEN (-2845 3607);
DISPLAY INVISIBLE (-2845 3607);
FORCEPROP 1 LAST SIZE 1B
J 0
(-2725 3600);
DISPLAY 0.872340 (-2725 3600);
PAINT AQUA (-2725 3600);
DISPLAY INVISIBLE (-2725 3600);
FORCEPROP 2 LAST CDS_LIB mstr_symbols
J 0
(-2800 3650);
PAINT MONO (-2800 3650);
DISPLAY INVISIBLE (-2800 3650);
FORCEPROP 1 LAST HDL_POWER GND
J 0
(-2800 3800);
DISPLAY 0.872340 (-2800 3800);
PAINT GREEN (-2800 3800);
DISPLAY INVISIBLE (-2800 3800);
FORCEPROP 1 LAST PATH I128
J 0
(-2725 3650);
DISPLAY 0.872340 (-2725 3650);
PAINT AQUA (-2725 3650);
DISPLAY INVISIBLE (-2725 3650);
FORCEADD RES..1
(-3325 3425);
FORCEPROP 1 LAST WATTAGE 1/16W
J 2
(-3350 3275);
DISPLAY 0.617021 (-3350 3275);
PAINT SKYBLUE (-3350 3275);
FORCEPROP 1 LAST VALUE 42.2
J 2
(-3350 3325);
DISPLAY 0.617021 (-3350 3325);
PAINT SKYBLUE (-3350 3325);
FORCEPROP 1 LASTPIN (-3425 3425) $PN 1
J 0
(-3413 3437);
DISPLAY 0.617021 (-3413 3437);
PAINT ORANGE (-3413 3437);
FORCEPROP 1 LAST LOCATION R7P3
J 0
(-3375 3475);
DISPLAY 0.617021 (-3375 3475);
PAINT AQUA (-3375 3475);
FORCEPROP 1 LAST MATERIAL EMPTY
J 0
(-3325 3275);
DISPLAY 0.617021 (-3325 3275);
PAINT RED (-3325 3275);
FORCEPROP 1 LAST TOLERANCE 1.0%
J 0
(-3325 3325);
DISPLAY 0.617021 (-3325 3325);
PAINT SKYBLUE (-3325 3325);
FORCEPROP 1 LASTPIN (-3225 3425) $PN 2
J 0
(-3263 3437);
DISPLAY 0.617021 (-3263 3437);
PAINT ORANGE (-3263 3437);
FORCEPROP 1 LAST PACK_TYPE 0402
J 0
(-3075 3275);
DISPLAY 0.617021 (-3075 3275);
PAINT SKYBLUE (-3075 3275);
FORCEPROP 1 LAST PART_NUMBER G21796-259
J 0
(-3175 3425);
DISPLAY 0.617021 (-3175 3425);
PAINT BLUE (-3175 3425);
FORCEPROP 2 LAST CDS_LOCATION R7P3
J 0
(-3375 3475);
DISPLAY 0.617021 (-3375 3475);
PAINT AQUA (-3375 3475);
DISPLAY INVISIBLE (-3375 3475);
FORCEPROP 2 LAST CDS_LIB mstr_discrete
J 0
(-3325 3425);
PAINT MONO (-3325 3425);
DISPLAY INVISIBLE (-3325 3425);
FORCEPROP 1 LAST PATH I129
J 0
(-3375 3575);
DISPLAY 0.978723 (-3375 3575);
PAINT WHITE (-3375 3575);
DISPLAY INVISIBLE (-3375 3575);
FORCEPROP 0 LAST ROOM DB1200Z
J 0
(-3375 3625);
DISPLAY 1.021277 (-3375 3625);
PAINT ORANGE (-3375 3625);
DISPLAY INVISIBLE (-3375 3625);
FORCEPROP 2 LAST SEC 1
J 0
(-3375 3625);
DISPLAY 0.680851 (-3375 3625);
PAINT MONO (-3375 3625);
DISPLAY INVISIBLE (-3375 3625);
FORCEPROP 2 LAST SEC_TYPE 0402
J 0
(-3375 3625);
DISPLAY 1.021277 (-3375 3625);
PAINT ORANGE (-3375 3625);
DISPLAY INVISIBLE (-3375 3625);
FORCEPROP 0 LAST BOM_COST SYS_CLOCK
J 0
(-3375 3725);
DISPLAY 1.021277 (-3375 3725);
PAINT ORANGE (-3375 3725);
DISPLAY INVISIBLE (-3375 3725);
FORCEADD GND..1
(-2800 3325);
FORCEPROP 3 LASTPIN (-2800 3375) SIG_NAME GND\g
J 0
(-2790 3385);
DISPLAY 0.659574 (-2790 3385);
PAINT MONO (-2790 3385);
DISPLAY INVISIBLE (-2790 3385);
FORCEPROP 1 LAST VOLTAGE 0.0V
J 0
(-2845 3282);
DISPLAY 0.340426 (-2845 3282);
PAINT SKYBLUE (-2845 3282);
DISPLAY INVISIBLE (-2845 3282);
FORCEPROP 1 LAST BODY_TYPE PLUMBING
J 0
(-2845 3282);
DISPLAY 0.340426 (-2845 3282);
PAINT GREEN (-2845 3282);
DISPLAY INVISIBLE (-2845 3282);
FORCEPROP 1 LAST SIZE 1B
J 0
(-2725 3275);
DISPLAY 0.872340 (-2725 3275);
PAINT AQUA (-2725 3275);
DISPLAY INVISIBLE (-2725 3275);
FORCEPROP 1 LAST PATH I130
J 0
(-2725 3325);
DISPLAY 0.872340 (-2725 3325);
PAINT AQUA (-2725 3325);
DISPLAY INVISIBLE (-2725 3325);
FORCEPROP 2 LAST CDS_LIB mstr_symbols
J 0
(-2800 3325);
PAINT MONO (-2800 3325);
DISPLAY INVISIBLE (-2800 3325);
FORCEPROP 1 LAST HDL_POWER GND
J 0
(-2800 3475);
DISPLAY 0.872340 (-2800 3475);
PAINT GREEN (-2800 3475);
DISPLAY INVISIBLE (-2800 3475);
FORCEADD RES..1
(-3325 3100);
FORCEPROP 1 LAST WATTAGE 1/16W
J 2
(-3350 2950);
DISPLAY 0.617021 (-3350 2950);
PAINT SKYBLUE (-3350 2950);
FORCEPROP 1 LAST VALUE 42.2
J 2
(-3350 3000);
DISPLAY 0.617021 (-3350 3000);
PAINT SKYBLUE (-3350 3000);
FORCEPROP 1 LAST TOLERANCE 1.0%
J 0
(-3325 3000);
DISPLAY 0.617021 (-3325 3000);
PAINT SKYBLUE (-3325 3000);
FORCEPROP 1 LAST MATERIAL EMPTY
J 0
(-3325 2950);
DISPLAY 0.617021 (-3325 2950);
PAINT RED (-3325 2950);
FORCEPROP 1 LASTPIN (-3425 3100) $PN 1
J 0
(-3413 3112);
DISPLAY 0.617021 (-3413 3112);
PAINT ORANGE (-3413 3112);
FORCEPROP 1 LAST LOCATION R7P4
J 0
(-3375 3150);
DISPLAY 0.617021 (-3375 3150);
PAINT AQUA (-3375 3150);
FORCEPROP 1 LASTPIN (-3225 3100) $PN 2
J 0
(-3263 3112);
DISPLAY 0.617021 (-3263 3112);
PAINT ORANGE (-3263 3112);
FORCEPROP 1 LAST PACK_TYPE 0402
J 0
(-3075 2950);
DISPLAY 0.617021 (-3075 2950);
PAINT SKYBLUE (-3075 2950);
FORCEPROP 1 LAST PART_NUMBER G21796-259
J 0
(-3175 3100);
DISPLAY 0.617021 (-3175 3100);
PAINT BLUE (-3175 3100);
FORCEPROP 2 LAST CDS_LOCATION R7P4
J 0
(-3375 3150);
DISPLAY 0.617021 (-3375 3150);
PAINT AQUA (-3375 3150);
DISPLAY INVISIBLE (-3375 3150);
FORCEPROP 1 LAST PATH I131
J 0
(-3375 3250);
DISPLAY 0.978723 (-3375 3250);
PAINT WHITE (-3375 3250);
DISPLAY INVISIBLE (-3375 3250);
FORCEPROP 0 LAST ROOM DB1200Z
J 0
(-3375 3300);
DISPLAY 1.021277 (-3375 3300);
PAINT ORANGE (-3375 3300);
DISPLAY INVISIBLE (-3375 3300);
FORCEPROP 2 LAST SEC 1
J 0
(-3375 3300);
DISPLAY 0.680851 (-3375 3300);
PAINT MONO (-3375 3300);
DISPLAY INVISIBLE (-3375 3300);
FORCEPROP 2 LAST SEC_TYPE 0402
J 0
(-3375 3300);
DISPLAY 1.021277 (-3375 3300);
PAINT ORANGE (-3375 3300);
DISPLAY INVISIBLE (-3375 3300);
FORCEPROP 0 LAST BOM_COST SYS_CLOCK
J 0
(-3375 3400);
DISPLAY 1.021277 (-3375 3400);
PAINT ORANGE (-3375 3400);
DISPLAY INVISIBLE (-3375 3400);
FORCEPROP 2 LAST CDS_LIB mstr_discrete
J 0
(-3325 3100);
PAINT MONO (-3325 3100);
DISPLAY INVISIBLE (-3325 3100);
FORCEADD GND..1
(-2800 3000);
FORCEPROP 3 LASTPIN (-2800 3050) SIG_NAME GND\g
J 0
(-2790 3060);
DISPLAY 0.659574 (-2790 3060);
PAINT MONO (-2790 3060);
DISPLAY INVISIBLE (-2790 3060);
FORCEPROP 1 LAST BODY_TYPE PLUMBING
J 0
(-2845 2957);
DISPLAY 0.340426 (-2845 2957);
PAINT GREEN (-2845 2957);
DISPLAY INVISIBLE (-2845 2957);
FORCEPROP 1 LAST VOLTAGE 0.0V
J 0
(-2845 2957);
DISPLAY 0.340426 (-2845 2957);
PAINT SKYBLUE (-2845 2957);
DISPLAY INVISIBLE (-2845 2957);
FORCEPROP 1 LAST PATH I132
J 0
(-2725 3000);
DISPLAY 0.872340 (-2725 3000);
PAINT AQUA (-2725 3000);
DISPLAY INVISIBLE (-2725 3000);
FORCEPROP 1 LAST SIZE 1B
J 0
(-2725 2950);
DISPLAY 0.872340 (-2725 2950);
PAINT AQUA (-2725 2950);
DISPLAY INVISIBLE (-2725 2950);
FORCEPROP 2 LAST CDS_LIB mstr_symbols
J 0
(-2800 3000);
PAINT MONO (-2800 3000);
DISPLAY INVISIBLE (-2800 3000);
FORCEPROP 1 LAST HDL_POWER GND
J 0
(-2800 3150);
DISPLAY 0.872340 (-2800 3150);
PAINT GREEN (-2800 3150);
DISPLAY INVISIBLE (-2800 3150);
FORCEADD RES..1
(-3325 2775);
FORCEPROP 1 LAST WATTAGE 1/16W
J 2
(-3350 2625);
DISPLAY 0.617021 (-3350 2625);
PAINT SKYBLUE (-3350 2625);
FORCEPROP 1 LAST VALUE 42.2
J 2
(-3350 2675);
DISPLAY 0.617021 (-3350 2675);
PAINT SKYBLUE (-3350 2675);
FORCEPROP 1 LASTPIN (-3425 2775) $PN 1
J 0
(-3413 2787);
DISPLAY 0.617021 (-3413 2787);
PAINT ORANGE (-3413 2787);
FORCEPROP 1 LAST LOCATION R7P1
J 0
(-3375 2825);
DISPLAY 0.617021 (-3375 2825);
PAINT AQUA (-3375 2825);
FORCEPROP 1 LAST TOLERANCE 1.0%
J 0
(-3325 2675);
DISPLAY 0.617021 (-3325 2675);
PAINT SKYBLUE (-3325 2675);
FORCEPROP 1 LASTPIN (-3225 2775) $PN 2
J 0
(-3263 2787);
DISPLAY 0.617021 (-3263 2787);
PAINT ORANGE (-3263 2787);
FORCEPROP 1 LAST MATERIAL EMPTY
J 0
(-3325 2625);
DISPLAY 0.617021 (-3325 2625);
PAINT RED (-3325 2625);
FORCEPROP 1 LAST PACK_TYPE 0402
J 0
(-3075 2625);
DISPLAY 0.617021 (-3075 2625);
PAINT SKYBLUE (-3075 2625);
FORCEPROP 1 LAST PART_NUMBER G21796-259
J 0
(-3175 2775);
DISPLAY 0.617021 (-3175 2775);
PAINT BLUE (-3175 2775);
FORCEPROP 2 LAST CDS_LOCATION R7P1
J 0
(-3375 2825);
DISPLAY 0.617021 (-3375 2825);
PAINT AQUA (-3375 2825);
DISPLAY INVISIBLE (-3375 2825);
FORCEPROP 1 LAST PATH I133
J 0
(-3375 2925);
DISPLAY 0.978723 (-3375 2925);
PAINT WHITE (-3375 2925);
DISPLAY INVISIBLE (-3375 2925);
FORCEPROP 0 LAST ROOM DB1200Z
J 0
(-3375 2975);
DISPLAY 1.021277 (-3375 2975);
PAINT ORANGE (-3375 2975);
DISPLAY INVISIBLE (-3375 2975);
FORCEPROP 2 LAST SEC 1
J 0
(-3375 2975);
DISPLAY 0.680851 (-3375 2975);
PAINT MONO (-3375 2975);
DISPLAY INVISIBLE (-3375 2975);
FORCEPROP 2 LAST SEC_TYPE 0402
J 0
(-3375 2975);
DISPLAY 1.021277 (-3375 2975);
PAINT ORANGE (-3375 2975);
DISPLAY INVISIBLE (-3375 2975);
FORCEPROP 2 LAST CDS_LIB mstr_discrete
J 0
(-3325 2775);
PAINT MONO (-3325 2775);
DISPLAY INVISIBLE (-3325 2775);
FORCEPROP 0 LAST BOM_COST SYS_CLOCK
J 0
(-3375 3075);
DISPLAY 1.021277 (-3375 3075);
PAINT ORANGE (-3375 3075);
DISPLAY INVISIBLE (-3375 3075);
FORCEADD GND..1
(-2800 2675);
FORCEPROP 3 LASTPIN (-2800 2725) SIG_NAME GND\g
J 0
(-2790 2735);
DISPLAY 0.659574 (-2790 2735);
PAINT MONO (-2790 2735);
DISPLAY INVISIBLE (-2790 2735);
FORCEPROP 1 LAST VOLTAGE 0.0V
J 0
(-2845 2632);
DISPLAY 0.340426 (-2845 2632);
PAINT SKYBLUE (-2845 2632);
DISPLAY INVISIBLE (-2845 2632);
FORCEPROP 1 LAST BODY_TYPE PLUMBING
J 0
(-2845 2632);
DISPLAY 0.340426 (-2845 2632);
PAINT GREEN (-2845 2632);
DISPLAY INVISIBLE (-2845 2632);
FORCEPROP 1 LAST PATH I134
J 0
(-2725 2675);
DISPLAY 0.872340 (-2725 2675);
PAINT AQUA (-2725 2675);
DISPLAY INVISIBLE (-2725 2675);
FORCEPROP 2 LAST CDS_LIB mstr_symbols
J 0
(-2800 2675);
PAINT MONO (-2800 2675);
DISPLAY INVISIBLE (-2800 2675);
FORCEPROP 1 LAST SIZE 1B
J 0
(-2725 2625);
DISPLAY 0.872340 (-2725 2625);
PAINT AQUA (-2725 2625);
DISPLAY INVISIBLE (-2725 2625);
FORCEPROP 1 LAST HDL_POWER GND
J 0
(-2800 2825);
DISPLAY 0.872340 (-2800 2825);
PAINT GREEN (-2800 2825);
DISPLAY INVISIBLE (-2800 2825);
FORCEADD RES..1
(-3325 2450);
FORCEPROP 1 LAST WATTAGE 1/16W
J 2
(-3350 2300);
DISPLAY 0.617021 (-3350 2300);
PAINT SKYBLUE (-3350 2300);
FORCEPROP 1 LAST VALUE 42.2
J 2
(-3350 2350);
DISPLAY 0.617021 (-3350 2350);
PAINT SKYBLUE (-3350 2350);
FORCEPROP 1 LASTPIN (-3425 2450) $PN 1
J 0
(-3413 2462);
DISPLAY 0.617021 (-3413 2462);
PAINT ORANGE (-3413 2462);
FORCEPROP 1 LAST LOCATION R7P2
J 0
(-3375 2500);
DISPLAY 0.617021 (-3375 2500);
PAINT AQUA (-3375 2500);
FORCEPROP 1 LAST MATERIAL EMPTY
J 0
(-3325 2300);
DISPLAY 0.617021 (-3325 2300);
PAINT RED (-3325 2300);
FORCEPROP 1 LAST TOLERANCE 1.0%
J 0
(-3325 2350);
DISPLAY 0.617021 (-3325 2350);
PAINT SKYBLUE (-3325 2350);
FORCEPROP 1 LASTPIN (-3225 2450) $PN 2
J 0
(-3263 2462);
DISPLAY 0.617021 (-3263 2462);
PAINT ORANGE (-3263 2462);
FORCEPROP 1 LAST PACK_TYPE 0402
J 0
(-3075 2300);
DISPLAY 0.617021 (-3075 2300);
PAINT SKYBLUE (-3075 2300);
FORCEPROP 1 LAST PART_NUMBER G21796-259
J 0
(-3175 2450);
DISPLAY 0.617021 (-3175 2450);
PAINT BLUE (-3175 2450);
FORCEPROP 2 LAST CDS_LOCATION R7P2
J 0
(-3375 2500);
DISPLAY 0.617021 (-3375 2500);
PAINT AQUA (-3375 2500);
DISPLAY INVISIBLE (-3375 2500);
FORCEPROP 2 LAST CDS_LIB mstr_discrete
J 0
(-3325 2450);
PAINT MONO (-3325 2450);
DISPLAY INVISIBLE (-3325 2450);
FORCEPROP 1 LAST PATH I135
J 0
(-3375 2600);
DISPLAY 0.978723 (-3375 2600);
PAINT WHITE (-3375 2600);
DISPLAY INVISIBLE (-3375 2600);
FORCEPROP 2 LAST SEC 1
J 0
(-3375 2650);
DISPLAY 0.680851 (-3375 2650);
PAINT MONO (-3375 2650);
DISPLAY INVISIBLE (-3375 2650);
FORCEPROP 0 LAST ROOM DB1200Z
J 0
(-3375 2650);
DISPLAY 1.021277 (-3375 2650);
PAINT ORANGE (-3375 2650);
DISPLAY INVISIBLE (-3375 2650);
FORCEPROP 2 LAST SEC_TYPE 0402
J 0
(-3375 2650);
DISPLAY 1.021277 (-3375 2650);
PAINT ORANGE (-3375 2650);
DISPLAY INVISIBLE (-3375 2650);
FORCEPROP 0 LAST BOM_COST SYS_CLOCK
J 0
(-3375 2750);
DISPLAY 1.021277 (-3375 2750);
PAINT ORANGE (-3375 2750);
DISPLAY INVISIBLE (-3375 2750);
FORCEADD GND..1
(-2800 2350);
FORCEPROP 3 LASTPIN (-2800 2400) SIG_NAME GND\g
J 0
(-2790 2410);
DISPLAY 0.659574 (-2790 2410);
PAINT MONO (-2790 2410);
DISPLAY INVISIBLE (-2790 2410);
FORCEPROP 1 LAST BODY_TYPE PLUMBING
J 0
(-2845 2307);
DISPLAY 0.340426 (-2845 2307);
PAINT GREEN (-2845 2307);
DISPLAY INVISIBLE (-2845 2307);
FORCEPROP 1 LAST VOLTAGE 0.0V
J 0
(-2845 2307);
DISPLAY 0.340426 (-2845 2307);
PAINT SKYBLUE (-2845 2307);
DISPLAY INVISIBLE (-2845 2307);
FORCEPROP 1 LAST SIZE 1B
J 0
(-2725 2300);
DISPLAY 0.872340 (-2725 2300);
PAINT AQUA (-2725 2300);
DISPLAY INVISIBLE (-2725 2300);
FORCEPROP 1 LAST HDL_POWER GND
J 0
(-2800 2500);
DISPLAY 0.872340 (-2800 2500);
PAINT GREEN (-2800 2500);
DISPLAY INVISIBLE (-2800 2500);
FORCEPROP 1 LAST PATH I136
J 0
(-2725 2350);
DISPLAY 0.872340 (-2725 2350);
PAINT AQUA (-2725 2350);
DISPLAY INVISIBLE (-2725 2350);
FORCEPROP 2 LAST CDS_LIB mstr_symbols
J 0
(-2800 2350);
PAINT MONO (-2800 2350);
DISPLAY INVISIBLE (-2800 2350);
FORCEADD RES..1
(-3325 2125);
FORCEPROP 1 LAST WATTAGE 1/16W
J 2
(-3350 1975);
DISPLAY 0.617021 (-3350 1975);
PAINT SKYBLUE (-3350 1975);
FORCEPROP 1 LAST MATERIAL EMPTY
J 0
(-3325 1975);
DISPLAY 0.617021 (-3325 1975);
PAINT RED (-3325 1975);
FORCEPROP 1 LAST PACK_TYPE 0402
J 0
(-3075 1975);
DISPLAY 0.617021 (-3075 1975);
PAINT SKYBLUE (-3075 1975);
FORCEPROP 1 LAST TOLERANCE 1.0%
J 0
(-3325 2025);
DISPLAY 0.617021 (-3325 2025);
PAINT SKYBLUE (-3325 2025);
FORCEPROP 1 LAST VALUE 42.2
J 2
(-3350 2025);
DISPLAY 0.617021 (-3350 2025);
PAINT SKYBLUE (-3350 2025);
FORCEPROP 1 LASTPIN (-3425 2125) $PN 1
J 0
(-3413 2137);
DISPLAY 0.617021 (-3413 2137);
PAINT ORANGE (-3413 2137);
FORCEPROP 1 LAST LOCATION R6P7
J 0
(-3375 2175);
DISPLAY 0.617021 (-3375 2175);
PAINT AQUA (-3375 2175);
FORCEPROP 1 LASTPIN (-3225 2125) $PN 2
J 0
(-3263 2137);
DISPLAY 0.617021 (-3263 2137);
PAINT ORANGE (-3263 2137);
FORCEPROP 1 LAST PART_NUMBER G21796-259
J 0
(-3175 2125);
DISPLAY 0.617021 (-3175 2125);
PAINT BLUE (-3175 2125);
FORCEPROP 2 LAST CDS_LOCATION R6P7
J 0
(-3375 2175);
DISPLAY 0.617021 (-3375 2175);
PAINT AQUA (-3375 2175);
DISPLAY INVISIBLE (-3375 2175);
FORCEPROP 1 LAST PATH I137
J 0
(-3375 2275);
DISPLAY 0.978723 (-3375 2275);
PAINT WHITE (-3375 2275);
DISPLAY INVISIBLE (-3375 2275);
FORCEPROP 0 LAST ROOM DB1200Z
J 0
(-3375 2325);
DISPLAY 1.021277 (-3375 2325);
PAINT ORANGE (-3375 2325);
DISPLAY INVISIBLE (-3375 2325);
FORCEPROP 2 LAST SEC 1
J 0
(-3375 2325);
DISPLAY 0.680851 (-3375 2325);
PAINT MONO (-3375 2325);
DISPLAY INVISIBLE (-3375 2325);
FORCEPROP 2 LAST SEC_TYPE 0402
J 0
(-3375 2325);
DISPLAY 1.021277 (-3375 2325);
PAINT ORANGE (-3375 2325);
DISPLAY INVISIBLE (-3375 2325);
FORCEPROP 0 LAST BOM_COST SYS_CLOCK
J 0
(-3375 2425);
DISPLAY 1.021277 (-3375 2425);
PAINT ORANGE (-3375 2425);
DISPLAY INVISIBLE (-3375 2425);
FORCEPROP 2 LAST CDS_LIB mstr_discrete
J 0
(-3325 2125);
PAINT MONO (-3325 2125);
DISPLAY INVISIBLE (-3325 2125);
FORCEADD GND..1
(-2800 2025);
FORCEPROP 3 LASTPIN (-2800 2075) SIG_NAME GND\g
J 0
(-2790 2085);
DISPLAY 0.659574 (-2790 2085);
PAINT MONO (-2790 2085);
DISPLAY INVISIBLE (-2790 2085);
FORCEPROP 1 LAST BODY_TYPE PLUMBING
J 0
(-2845 1982);
DISPLAY 0.340426 (-2845 1982);
PAINT GREEN (-2845 1982);
DISPLAY INVISIBLE (-2845 1982);
FORCEPROP 1 LAST VOLTAGE 0.0V
J 0
(-2845 1982);
DISPLAY 0.340426 (-2845 1982);
PAINT SKYBLUE (-2845 1982);
DISPLAY INVISIBLE (-2845 1982);
FORCEPROP 1 LAST SIZE 1B
J 0
(-2725 1975);
DISPLAY 0.872340 (-2725 1975);
PAINT AQUA (-2725 1975);
DISPLAY INVISIBLE (-2725 1975);
FORCEPROP 1 LAST PATH I138
J 0
(-2725 2025);
DISPLAY 0.872340 (-2725 2025);
PAINT AQUA (-2725 2025);
DISPLAY INVISIBLE (-2725 2025);
FORCEPROP 2 LAST CDS_LIB mstr_symbols
J 0
(-2800 2025);
PAINT MONO (-2800 2025);
DISPLAY INVISIBLE (-2800 2025);
FORCEPROP 1 LAST HDL_POWER GND
J 0
(-2800 2175);
DISPLAY 0.872340 (-2800 2175);
PAINT GREEN (-2800 2175);
DISPLAY INVISIBLE (-2800 2175);
FORCEADD RES..1
(-3325 1800);
FORCEPROP 1 LAST WATTAGE 1/16W
J 2
(-3350 1650);
DISPLAY 0.617021 (-3350 1650);
PAINT SKYBLUE (-3350 1650);
FORCEPROP 1 LAST VALUE 42.2
J 2
(-3350 1700);
DISPLAY 0.617021 (-3350 1700);
PAINT SKYBLUE (-3350 1700);
FORCEPROP 1 LASTPIN (-3425 1800) $PN 1
J 0
(-3413 1812);
DISPLAY 0.617021 (-3413 1812);
PAINT ORANGE (-3413 1812);
FORCEPROP 1 LAST LOCATION R6P8
J 0
(-3375 1850);
DISPLAY 0.617021 (-3375 1850);
PAINT AQUA (-3375 1850);
FORCEPROP 1 LAST TOLERANCE 1.0%
J 0
(-3325 1700);
DISPLAY 0.617021 (-3325 1700);
PAINT SKYBLUE (-3325 1700);
FORCEPROP 1 LAST MATERIAL EMPTY
J 0
(-3325 1650);
DISPLAY 0.617021 (-3325 1650);
PAINT RED (-3325 1650);
FORCEPROP 1 LASTPIN (-3225 1800) $PN 2
J 0
(-3263 1812);
DISPLAY 0.617021 (-3263 1812);
PAINT ORANGE (-3263 1812);
FORCEPROP 1 LAST PACK_TYPE 0402
J 0
(-3075 1650);
DISPLAY 0.617021 (-3075 1650);
PAINT SKYBLUE (-3075 1650);
FORCEPROP 1 LAST PART_NUMBER G21796-259
J 0
(-3175 1800);
DISPLAY 0.617021 (-3175 1800);
PAINT BLUE (-3175 1800);
FORCEPROP 2 LAST CDS_LOCATION R6P8
J 0
(-3375 1850);
DISPLAY 0.617021 (-3375 1850);
PAINT AQUA (-3375 1850);
DISPLAY INVISIBLE (-3375 1850);
FORCEPROP 0 LAST ROOM DB1200Z
J 0
(-3375 2000);
DISPLAY 1.021277 (-3375 2000);
PAINT ORANGE (-3375 2000);
DISPLAY INVISIBLE (-3375 2000);
FORCEPROP 1 LAST PATH I139
J 0
(-3375 1950);
DISPLAY 0.978723 (-3375 1950);
PAINT WHITE (-3375 1950);
DISPLAY INVISIBLE (-3375 1950);
FORCEPROP 2 LAST SEC_TYPE 0402
J 0
(-3375 2000);
DISPLAY 1.021277 (-3375 2000);
PAINT ORANGE (-3375 2000);
DISPLAY INVISIBLE (-3375 2000);
FORCEPROP 2 LAST SEC 1
J 0
(-3375 2000);
DISPLAY 0.680851 (-3375 2000);
PAINT MONO (-3375 2000);
DISPLAY INVISIBLE (-3375 2000);
FORCEPROP 2 LAST CDS_LIB mstr_discrete
J 0
(-3325 1800);
PAINT MONO (-3325 1800);
DISPLAY INVISIBLE (-3325 1800);
FORCEPROP 0 LAST BOM_COST SYS_CLOCK
J 0
(-3375 2100);
DISPLAY 1.021277 (-3375 2100);
PAINT ORANGE (-3375 2100);
DISPLAY INVISIBLE (-3375 2100);
FORCEADD RES..1
(-3925 4525);
FORCEPROP 1 LAST VALUE 27.4
J 2
(-4000 4475);
DISPLAY 0.617021 (-4000 4475);
PAINT SKYBLUE (-4000 4475);
FORCEPROP 1 LASTPIN (-4025 4525) $PN 1
J 0
(-4013 4537);
DISPLAY 0.617021 (-4013 4537);
PAINT ORANGE (-4013 4537);
FORCEPROP 1 LAST WATTAGE 1/16W
J 2
(-3950 4425);
DISPLAY 0.617021 (-3950 4425);
PAINT SKYBLUE (-3950 4425);
FORCEPROP 1 LAST TOLERANCE 1%
J 0
(-3925 4425);
DISPLAY 0.617021 (-3925 4425);
PAINT SKYBLUE (-3925 4425);
FORCEPROP 1 LASTPIN (-3825 4525) $PN 2
J 0
(-3863 4537);
DISPLAY 0.617021 (-3863 4537);
PAINT ORANGE (-3863 4537);
FORCEPROP 1 LAST MATERIAL CHIP
J 0
(-3875 4475);
DISPLAY 0.617021 (-3875 4475);
PAINT SKYBLUE (-3875 4475);
FORCEPROP 1 LAST PACK_TYPE 0402
J 0
(-3850 4425);
DISPLAY 0.617021 (-3850 4425);
PAINT SKYBLUE (-3850 4425);
FORCEPROP 1 LAST PART_NUMBER G21796-182
J 0
(-4050 4375);
DISPLAY 0.617021 (-4050 4375);
PAINT BLUE (-4050 4375);
FORCEPROP 1 LAST LOCATION R4D28
J 0
(-3975 4575);
DISPLAY 0.617021 (-3975 4575);
PAINT AQUA (-3975 4575);
FORCEPROP 2 LAST CDS_LOCATION R4D28
J 0
(-3975 4575);
DISPLAY 0.617021 (-3975 4575);
PAINT AQUA (-3975 4575);
DISPLAY INVISIBLE (-3975 4575);
FORCEPROP 2 LAST CDS_LIB mstr_discrete
J 0
(-3925 4525);
PAINT ORANGE (-3925 4525);
DISPLAY INVISIBLE (-3925 4525);
FORCEPROP 0 LAST ROOM DB1200Z
J 0
(-3975 4675);
DISPLAY 1.021277 (-3975 4675);
PAINT ORANGE (-3975 4675);
DISPLAY INVISIBLE (-3975 4675);
FORCEPROP 1 LAST PATH I14
J 0
(-3975 4675);
DISPLAY 0.978723 (-3975 4675);
PAINT WHITE (-3975 4675);
DISPLAY INVISIBLE (-3975 4675);
FORCEPROP 2 LAST SEC 1
J 0
(-3975 4725);
DISPLAY 0.680851 (-3975 4725);
PAINT MONO (-3975 4725);
DISPLAY INVISIBLE (-3975 4725);
FORCEPROP 0 LAST BOM_COST SYS_CLOCK
J 0
(-3975 4775);
DISPLAY 1.021277 (-3975 4775);
PAINT ORANGE (-3975 4775);
DISPLAY INVISIBLE (-3975 4775);
FORCEPROP 2 LAST SEC_TYPE 0402
J 0
(-3975 4725);
DISPLAY 1.021277 (-3975 4725);
PAINT ORANGE (-3975 4725);
DISPLAY INVISIBLE (-3975 4725);
FORCEADD GND..1
(-2800 1700);
FORCEPROP 3 LASTPIN (-2800 1750) SIG_NAME GND\g
J 0
(-2790 1760);
DISPLAY 0.659574 (-2790 1760);
PAINT MONO (-2790 1760);
DISPLAY INVISIBLE (-2790 1760);
FORCEPROP 1 LAST BODY_TYPE PLUMBING
J 0
(-2845 1657);
DISPLAY 0.340426 (-2845 1657);
PAINT GREEN (-2845 1657);
DISPLAY INVISIBLE (-2845 1657);
FORCEPROP 1 LAST VOLTAGE 0.0V
J 0
(-2845 1657);
DISPLAY 0.340426 (-2845 1657);
PAINT SKYBLUE (-2845 1657);
DISPLAY INVISIBLE (-2845 1657);
FORCEPROP 1 LAST PATH I140
J 0
(-2725 1700);
DISPLAY 0.872340 (-2725 1700);
PAINT AQUA (-2725 1700);
DISPLAY INVISIBLE (-2725 1700);
FORCEPROP 1 LAST SIZE 1B
J 0
(-2725 1650);
DISPLAY 0.872340 (-2725 1650);
PAINT AQUA (-2725 1650);
DISPLAY INVISIBLE (-2725 1650);
FORCEPROP 2 LAST CDS_LIB mstr_symbols
J 0
(-2800 1700);
PAINT MONO (-2800 1700);
DISPLAY INVISIBLE (-2800 1700);
FORCEPROP 1 LAST HDL_POWER GND
J 0
(-2800 1850);
DISPLAY 0.872340 (-2800 1850);
PAINT GREEN (-2800 1850);
DISPLAY INVISIBLE (-2800 1850);
FORCEADD RES..1
(-3325 1475);
FORCEPROP 1 LAST WATTAGE 1/16W
J 2
(-3350 1325);
DISPLAY 0.617021 (-3350 1325);
PAINT SKYBLUE (-3350 1325);
FORCEPROP 1 LAST VALUE 42.2
J 2
(-3350 1375);
DISPLAY 0.617021 (-3350 1375);
PAINT SKYBLUE (-3350 1375);
FORCEPROP 1 LASTPIN (-3425 1475) $PN 1
J 0
(-3413 1487);
DISPLAY 0.617021 (-3413 1487);
PAINT ORANGE (-3413 1487);
FORCEPROP 1 LAST TOLERANCE 1.0%
J 0
(-3325 1375);
DISPLAY 0.617021 (-3325 1375);
PAINT SKYBLUE (-3325 1375);
FORCEPROP 1 LASTPIN (-3225 1475) $PN 2
J 0
(-3263 1487);
DISPLAY 0.617021 (-3263 1487);
PAINT ORANGE (-3263 1487);
FORCEPROP 1 LAST MATERIAL EMPTY
J 0
(-3325 1325);
DISPLAY 0.617021 (-3325 1325);
PAINT RED (-3325 1325);
FORCEPROP 1 LAST LOCATION R6P5
J 0
(-3375 1525);
DISPLAY 0.617021 (-3375 1525);
PAINT AQUA (-3375 1525);
FORCEPROP 1 LAST PACK_TYPE 0402
J 0
(-3075 1325);
DISPLAY 0.617021 (-3075 1325);
PAINT SKYBLUE (-3075 1325);
FORCEPROP 1 LAST PART_NUMBER G21796-259
J 0
(-3175 1475);
DISPLAY 0.617021 (-3175 1475);
PAINT BLUE (-3175 1475);
FORCEPROP 2 LAST CDS_LIB mstr_discrete
J 0
(-3325 1475);
PAINT MONO (-3325 1475);
DISPLAY INVISIBLE (-3325 1475);
FORCEPROP 2 LAST CDS_LOCATION R6P5
J 0
(-3375 1525);
DISPLAY 0.617021 (-3375 1525);
PAINT AQUA (-3375 1525);
DISPLAY INVISIBLE (-3375 1525);
FORCEPROP 1 LAST PATH I141
J 0
(-3375 1625);
DISPLAY 0.978723 (-3375 1625);
PAINT WHITE (-3375 1625);
DISPLAY INVISIBLE (-3375 1625);
FORCEPROP 0 LAST ROOM DB1200Z
J 0
(-3375 1675);
DISPLAY 1.021277 (-3375 1675);
PAINT ORANGE (-3375 1675);
DISPLAY INVISIBLE (-3375 1675);
FORCEPROP 2 LAST SEC 1
J 0
(-3375 1675);
DISPLAY 0.680851 (-3375 1675);
PAINT MONO (-3375 1675);
DISPLAY INVISIBLE (-3375 1675);
FORCEPROP 2 LAST SEC_TYPE 0402
J 0
(-3375 1675);
DISPLAY 1.021277 (-3375 1675);
PAINT ORANGE (-3375 1675);
DISPLAY INVISIBLE (-3375 1675);
FORCEPROP 0 LAST BOM_COST SYS_CLOCK
J 0
(-3375 1775);
DISPLAY 1.021277 (-3375 1775);
PAINT ORANGE (-3375 1775);
DISPLAY INVISIBLE (-3375 1775);
FORCEADD GND..1
(-2800 1375);
FORCEPROP 3 LASTPIN (-2800 1425) SIG_NAME GND\g
J 0
(-2790 1435);
DISPLAY 0.659574 (-2790 1435);
PAINT MONO (-2790 1435);
DISPLAY INVISIBLE (-2790 1435);
FORCEPROP 1 LAST BODY_TYPE PLUMBING
J 0
(-2845 1332);
DISPLAY 0.340426 (-2845 1332);
PAINT GREEN (-2845 1332);
DISPLAY INVISIBLE (-2845 1332);
FORCEPROP 1 LAST VOLTAGE 0.0V
J 0
(-2845 1332);
DISPLAY 0.340426 (-2845 1332);
PAINT SKYBLUE (-2845 1332);
DISPLAY INVISIBLE (-2845 1332);
FORCEPROP 1 LAST PATH I142
J 0
(-2725 1375);
DISPLAY 0.872340 (-2725 1375);
PAINT AQUA (-2725 1375);
DISPLAY INVISIBLE (-2725 1375);
FORCEPROP 1 LAST SIZE 1B
J 0
(-2725 1325);
DISPLAY 0.872340 (-2725 1325);
PAINT AQUA (-2725 1325);
DISPLAY INVISIBLE (-2725 1325);
FORCEPROP 2 LAST CDS_LIB mstr_symbols
J 0
(-2800 1375);
PAINT MONO (-2800 1375);
DISPLAY INVISIBLE (-2800 1375);
FORCEPROP 1 LAST HDL_POWER GND
J 0
(-2800 1525);
DISPLAY 0.872340 (-2800 1525);
PAINT GREEN (-2800 1525);
DISPLAY INVISIBLE (-2800 1525);
FORCEADD RES..1
(-3325 1150);
FORCEPROP 1 LAST WATTAGE 1/16W
J 2
(-3350 1000);
DISPLAY 0.617021 (-3350 1000);
PAINT SKYBLUE (-3350 1000);
FORCEPROP 1 LAST MATERIAL EMPTY
J 0
(-3325 1000);
DISPLAY 0.617021 (-3325 1000);
PAINT RED (-3325 1000);
FORCEPROP 1 LAST VALUE 42.2
J 2
(-3350 1050);
DISPLAY 0.617021 (-3350 1050);
PAINT SKYBLUE (-3350 1050);
FORCEPROP 1 LASTPIN (-3425 1150) $PN 1
J 0
(-3413 1162);
DISPLAY 0.617021 (-3413 1162);
PAINT ORANGE (-3413 1162);
FORCEPROP 1 LAST LOCATION R6P6
J 0
(-3375 1200);
DISPLAY 0.617021 (-3375 1200);
PAINT AQUA (-3375 1200);
FORCEPROP 1 LAST TOLERANCE 1.0%
J 0
(-3325 1050);
DISPLAY 0.617021 (-3325 1050);
PAINT SKYBLUE (-3325 1050);
FORCEPROP 1 LASTPIN (-3225 1150) $PN 2
J 0
(-3263 1162);
DISPLAY 0.617021 (-3263 1162);
PAINT ORANGE (-3263 1162);
FORCEPROP 1 LAST PACK_TYPE 0402
J 0
(-3075 1000);
DISPLAY 0.617021 (-3075 1000);
PAINT SKYBLUE (-3075 1000);
FORCEPROP 1 LAST PART_NUMBER G21796-259
J 0
(-3175 1150);
DISPLAY 0.617021 (-3175 1150);
PAINT BLUE (-3175 1150);
FORCEPROP 2 LAST CDS_LOCATION R6P6
J 0
(-3375 1200);
DISPLAY 0.617021 (-3375 1200);
PAINT AQUA (-3375 1200);
DISPLAY INVISIBLE (-3375 1200);
FORCEPROP 0 LAST ROOM DB1200Z
J 0
(-3375 1350);
DISPLAY 1.021277 (-3375 1350);
PAINT ORANGE (-3375 1350);
DISPLAY INVISIBLE (-3375 1350);
FORCEPROP 1 LAST PATH I143
J 0
(-3375 1300);
DISPLAY 0.978723 (-3375 1300);
PAINT WHITE (-3375 1300);
DISPLAY INVISIBLE (-3375 1300);
FORCEPROP 2 LAST SEC 1
J 0
(-3375 1350);
DISPLAY 0.680851 (-3375 1350);
PAINT MONO (-3375 1350);
DISPLAY INVISIBLE (-3375 1350);
FORCEPROP 2 LAST SEC_TYPE 0402
J 0
(-3375 1350);
DISPLAY 1.021277 (-3375 1350);
PAINT ORANGE (-3375 1350);
DISPLAY INVISIBLE (-3375 1350);
FORCEPROP 0 LAST BOM_COST SYS_CLOCK
J 0
(-3375 1450);
DISPLAY 1.021277 (-3375 1450);
PAINT ORANGE (-3375 1450);
DISPLAY INVISIBLE (-3375 1450);
FORCEPROP 2 LAST CDS_LIB mstr_discrete
J 0
(-3325 1150);
PAINT MONO (-3325 1150);
DISPLAY INVISIBLE (-3325 1150);
FORCEADD GND..1
(-2800 1050);
FORCEPROP 3 LASTPIN (-2800 1100) SIG_NAME GND\g
J 0
(-2790 1110);
DISPLAY 0.659574 (-2790 1110);
PAINT MONO (-2790 1110);
DISPLAY INVISIBLE (-2790 1110);
FORCEPROP 1 LAST BODY_TYPE PLUMBING
J 0
(-2845 1007);
DISPLAY 0.340426 (-2845 1007);
PAINT GREEN (-2845 1007);
DISPLAY INVISIBLE (-2845 1007);
FORCEPROP 1 LAST VOLTAGE 0.0V
J 0
(-2845 1007);
DISPLAY 0.340426 (-2845 1007);
PAINT SKYBLUE (-2845 1007);
DISPLAY INVISIBLE (-2845 1007);
FORCEPROP 1 LAST SIZE 1B
J 0
(-2725 1000);
DISPLAY 0.872340 (-2725 1000);
PAINT AQUA (-2725 1000);
DISPLAY INVISIBLE (-2725 1000);
FORCEPROP 2 LAST CDS_LIB mstr_symbols
J 0
(-2800 1050);
PAINT MONO (-2800 1050);
DISPLAY INVISIBLE (-2800 1050);
FORCEPROP 1 LAST HDL_POWER GND
J 0
(-2800 1200);
DISPLAY 0.872340 (-2800 1200);
PAINT GREEN (-2800 1200);
DISPLAY INVISIBLE (-2800 1200);
FORCEPROP 1 LAST PATH I144
J 0
(-2725 1050);
DISPLAY 0.872340 (-2725 1050);
PAINT AQUA (-2725 1050);
DISPLAY INVISIBLE (-2725 1050);
FORCEADD RES..1
(1025 4725);
FORCEPROP 1 LAST WATTAGE 1/16W
J 2
(1000 4575);
DISPLAY 0.617021 (1000 4575);
PAINT SKYBLUE (1000 4575);
FORCEPROP 1 LAST VALUE 42.2
J 2
(1000 4625);
DISPLAY 0.617021 (1000 4625);
PAINT SKYBLUE (1000 4625);
FORCEPROP 1 LASTPIN (925 4725) $PN 1
J 0
(937 4737);
DISPLAY 0.617021 (937 4737);
PAINT ORANGE (937 4737);
FORCEPROP 1 LAST LOCATION R6P3
J 0
(975 4775);
DISPLAY 0.617021 (975 4775);
PAINT AQUA (975 4775);
FORCEPROP 1 LAST MATERIAL EMPTY
J 0
(1025 4575);
DISPLAY 0.617021 (1025 4575);
PAINT RED (1025 4575);
FORCEPROP 1 LAST PACK_TYPE 0402
J 0
(1275 4575);
DISPLAY 0.617021 (1275 4575);
PAINT SKYBLUE (1275 4575);
FORCEPROP 1 LAST TOLERANCE 1.0%
J 0
(1025 4625);
DISPLAY 0.617021 (1025 4625);
PAINT SKYBLUE (1025 4625);
FORCEPROP 1 LASTPIN (1125 4725) $PN 2
J 0
(1087 4737);
DISPLAY 0.617021 (1087 4737);
PAINT ORANGE (1087 4737);
FORCEPROP 1 LAST PART_NUMBER G21796-259
J 0
(1175 4725);
DISPLAY 0.617021 (1175 4725);
PAINT BLUE (1175 4725);
FORCEPROP 2 LAST CDS_LOCATION R6P3
J 0
(975 4775);
DISPLAY 0.617021 (975 4775);
PAINT AQUA (975 4775);
DISPLAY INVISIBLE (975 4775);
FORCEPROP 0 LAST ROOM DB1200Z
J 0
(975 4925);
DISPLAY 1.021277 (975 4925);
PAINT ORANGE (975 4925);
DISPLAY INVISIBLE (975 4925);
FORCEPROP 1 LAST PATH I145
J 0
(975 4875);
DISPLAY 0.978723 (975 4875);
PAINT WHITE (975 4875);
DISPLAY INVISIBLE (975 4875);
FORCEPROP 2 LAST SEC 1
J 0
(975 4925);
DISPLAY 0.680851 (975 4925);
PAINT MONO (975 4925);
DISPLAY INVISIBLE (975 4925);
FORCEPROP 0 LAST BOM_COST SYS_CLOCK
J 0
(975 5025);
DISPLAY 1.021277 (975 5025);
PAINT ORANGE (975 5025);
DISPLAY INVISIBLE (975 5025);
FORCEPROP 2 LAST SEC_TYPE 0402
J 0
(975 4925);
DISPLAY 1.021277 (975 4925);
PAINT ORANGE (975 4925);
DISPLAY INVISIBLE (975 4925);
FORCEPROP 2 LAST CDS_LIB mstr_discrete
J 0
(1025 4725);
PAINT MONO (1025 4725);
DISPLAY INVISIBLE (1025 4725);
FORCEADD GND..1
(1550 4625);
FORCEPROP 3 LASTPIN (1550 4675) SIG_NAME GND\g
J 0
(1560 4685);
DISPLAY 0.659574 (1560 4685);
PAINT MONO (1560 4685);
DISPLAY INVISIBLE (1560 4685);
FORCEPROP 1 LAST BODY_TYPE PLUMBING
J 0
(1505 4582);
DISPLAY 0.340426 (1505 4582);
PAINT GREEN (1505 4582);
DISPLAY INVISIBLE (1505 4582);
FORCEPROP 1 LAST VOLTAGE 0.0V
J 0
(1505 4582);
DISPLAY 0.340426 (1505 4582);
PAINT SKYBLUE (1505 4582);
DISPLAY INVISIBLE (1505 4582);
FORCEPROP 1 LAST SIZE 1B
J 0
(1625 4575);
DISPLAY 0.872340 (1625 4575);
PAINT AQUA (1625 4575);
DISPLAY INVISIBLE (1625 4575);
FORCEPROP 1 LAST HDL_POWER GND
J 0
(1550 4775);
DISPLAY 0.872340 (1550 4775);
PAINT GREEN (1550 4775);
DISPLAY INVISIBLE (1550 4775);
FORCEPROP 2 LAST CDS_LIB mstr_symbols
J 0
(1550 4625);
PAINT MONO (1550 4625);
DISPLAY INVISIBLE (1550 4625);
FORCEPROP 1 LAST PATH I146
J 0
(1625 4625);
DISPLAY 0.872340 (1625 4625);
PAINT AQUA (1625 4625);
DISPLAY INVISIBLE (1625 4625);
FORCEADD RES..1
(1050 4400);
FORCEPROP 1 LASTPIN (950 4400) $PN 1
J 0
(962 4412);
DISPLAY 0.617021 (962 4412);
PAINT ORANGE (962 4412);
FORCEPROP 1 LAST WATTAGE 1/16W
J 2
(1025 4250);
DISPLAY 0.617021 (1025 4250);
PAINT SKYBLUE (1025 4250);
FORCEPROP 1 LAST VALUE 42.2
J 2
(1025 4300);
DISPLAY 0.617021 (1025 4300);
PAINT SKYBLUE (1025 4300);
FORCEPROP 1 LAST LOCATION R6P4
J 0
(1000 4450);
DISPLAY 0.617021 (1000 4450);
PAINT AQUA (1000 4450);
FORCEPROP 1 LAST TOLERANCE 1.0%
J 0
(1050 4300);
DISPLAY 0.617021 (1050 4300);
PAINT SKYBLUE (1050 4300);
FORCEPROP 1 LAST MATERIAL EMPTY
J 0
(1050 4250);
DISPLAY 0.617021 (1050 4250);
PAINT RED (1050 4250);
FORCEPROP 1 LASTPIN (1150 4400) $PN 2
J 0
(1112 4412);
DISPLAY 0.617021 (1112 4412);
PAINT ORANGE (1112 4412);
FORCEPROP 1 LAST PART_NUMBER G21796-259
J 0
(1200 4400);
DISPLAY 0.617021 (1200 4400);
PAINT BLUE (1200 4400);
FORCEPROP 1 LAST PACK_TYPE 0402
J 0
(1300 4250);
DISPLAY 0.617021 (1300 4250);
PAINT SKYBLUE (1300 4250);
FORCEPROP 2 LAST CDS_LOCATION R6P4
J 0
(1000 4450);
DISPLAY 0.617021 (1000 4450);
PAINT AQUA (1000 4450);
DISPLAY INVISIBLE (1000 4450);
FORCEPROP 1 LAST PATH I147
J 0
(1000 4550);
DISPLAY 0.978723 (1000 4550);
PAINT WHITE (1000 4550);
DISPLAY INVISIBLE (1000 4550);
FORCEPROP 0 LAST ROOM DB1200Z
J 0
(1000 4600);
DISPLAY 1.021277 (1000 4600);
PAINT ORANGE (1000 4600);
DISPLAY INVISIBLE (1000 4600);
FORCEPROP 2 LAST SEC 1
J 0
(1000 4600);
DISPLAY 0.680851 (1000 4600);
PAINT MONO (1000 4600);
DISPLAY INVISIBLE (1000 4600);
FORCEPROP 2 LAST SEC_TYPE 0402
J 0
(1000 4600);
DISPLAY 1.021277 (1000 4600);
PAINT ORANGE (1000 4600);
DISPLAY INVISIBLE (1000 4600);
FORCEPROP 0 LAST BOM_COST SYS_CLOCK
J 0
(1000 4700);
DISPLAY 1.021277 (1000 4700);
PAINT ORANGE (1000 4700);
DISPLAY INVISIBLE (1000 4700);
FORCEPROP 2 LAST CDS_LIB mstr_discrete
J 0
(1050 4400);
PAINT MONO (1050 4400);
DISPLAY INVISIBLE (1050 4400);
FORCEADD GND..1
(1575 4300);
FORCEPROP 3 LASTPIN (1575 4350) SIG_NAME GND\g
J 0
(1585 4360);
DISPLAY 0.659574 (1585 4360);
PAINT MONO (1585 4360);
DISPLAY INVISIBLE (1585 4360);
FORCEPROP 1 LAST BODY_TYPE PLUMBING
J 0
(1530 4257);
DISPLAY 0.340426 (1530 4257);
PAINT GREEN (1530 4257);
DISPLAY INVISIBLE (1530 4257);
FORCEPROP 1 LAST VOLTAGE 0.0V
J 0
(1530 4257);
DISPLAY 0.340426 (1530 4257);
PAINT SKYBLUE (1530 4257);
DISPLAY INVISIBLE (1530 4257);
FORCEPROP 1 LAST SIZE 1B
J 0
(1650 4250);
DISPLAY 0.872340 (1650 4250);
PAINT AQUA (1650 4250);
DISPLAY INVISIBLE (1650 4250);
FORCEPROP 2 LAST CDS_LIB mstr_symbols
J 0
(1575 4300);
PAINT MONO (1575 4300);
DISPLAY INVISIBLE (1575 4300);
FORCEPROP 1 LAST PATH I148
J 0
(1650 4300);
DISPLAY 0.872340 (1650 4300);
PAINT AQUA (1650 4300);
DISPLAY INVISIBLE (1650 4300);
FORCEPROP 1 LAST HDL_POWER GND
J 0
(1575 4450);
DISPLAY 0.872340 (1575 4450);
PAINT GREEN (1575 4450);
DISPLAY INVISIBLE (1575 4450);
FORCEADD RES..1
(1025 4075);
FORCEPROP 1 LAST WATTAGE 1/16W
J 2
(1000 3925);
DISPLAY 0.617021 (1000 3925);
PAINT SKYBLUE (1000 3925);
FORCEPROP 1 LAST VALUE 42.2
J 2
(1000 3975);
DISPLAY 0.617021 (1000 3975);
PAINT SKYBLUE (1000 3975);
FORCEPROP 1 LAST TOLERANCE 1.0%
J 0
(1025 3975);
DISPLAY 0.617021 (1025 3975);
PAINT SKYBLUE (1025 3975);
FORCEPROP 1 LAST MATERIAL EMPTY
J 0
(1025 3925);
DISPLAY 0.617021 (1025 3925);
PAINT RED (1025 3925);
FORCEPROP 1 LAST PACK_TYPE 0402
J 0
(1275 3925);
DISPLAY 0.617021 (1275 3925);
PAINT SKYBLUE (1275 3925);
FORCEPROP 1 LASTPIN (925 4075) $PN 1
J 0
(937 4087);
DISPLAY 0.617021 (937 4087);
PAINT ORANGE (937 4087);
FORCEPROP 1 LASTPIN (1125 4075) $PN 2
J 0
(1087 4087);
DISPLAY 0.617021 (1087 4087);
PAINT ORANGE (1087 4087);
FORCEPROP 1 LAST PART_NUMBER G21796-259
J 0
(1175 4075);
DISPLAY 0.617021 (1175 4075);
PAINT BLUE (1175 4075);
FORCEPROP 1 LAST LOCATION R6P1
J 0
(975 4125);
DISPLAY 0.617021 (975 4125);
PAINT AQUA (975 4125);
FORCEPROP 2 LAST CDS_LIB mstr_discrete
J 0
(1025 4075);
PAINT MONO (1025 4075);
DISPLAY INVISIBLE (1025 4075);
FORCEPROP 2 LAST CDS_LOCATION R6P1
J 0
(975 4125);
DISPLAY 0.617021 (975 4125);
PAINT AQUA (975 4125);
DISPLAY INVISIBLE (975 4125);
FORCEPROP 0 LAST ROOM DB1200Z
J 0
(975 4275);
DISPLAY 1.021277 (975 4275);
PAINT ORANGE (975 4275);
DISPLAY INVISIBLE (975 4275);
FORCEPROP 1 LAST PATH I149
J 0
(975 4225);
DISPLAY 0.978723 (975 4225);
PAINT WHITE (975 4225);
DISPLAY INVISIBLE (975 4225);
FORCEPROP 2 LAST SEC 1
J 0
(975 4275);
DISPLAY 0.680851 (975 4275);
PAINT MONO (975 4275);
DISPLAY INVISIBLE (975 4275);
FORCEPROP 2 LAST SEC_TYPE 0402
J 0
(975 4275);
DISPLAY 1.021277 (975 4275);
PAINT ORANGE (975 4275);
DISPLAY INVISIBLE (975 4275);
FORCEPROP 0 LAST BOM_COST SYS_CLOCK
J 0
(975 4375);
DISPLAY 1.021277 (975 4375);
PAINT ORANGE (975 4375);
DISPLAY INVISIBLE (975 4375);
FORCEADD OFFPAGE..1
(-4900 4525);
FORCEPROP 2 LAST $XR0 102 
J 0
(-5152 4525);
DISPLAY 0.638298 (-5152 4525);
PAINT MONO (-5152 4525);
FORCEPROP 2 LAST CDS_LIB mstr_standard
J 0
(-4900 4525);
PAINT ORANGE (-4900 4525);
DISPLAY INVISIBLE (-4900 4525);
FORCEPROP 1 LAST COMMENT_BODY TRUE
J 0
(-4775 4425);
DISPLAY 0.872340 (-4775 4425);
PAINT GREEN (-4775 4425);
DISPLAY INVISIBLE (-4775 4425);
FORCEPROP 2 LAST PATH I15
J 0
(-4850 4600);
DISPLAY 1.021277 (-4850 4600);
PAINT ORANGE (-4850 4600);
DISPLAY INVISIBLE (-4850 4600);
FORCEPROP 1 LAST OFFPAGE TRUE
J 0
(-4575 4400);
DISPLAY 0.872340 (-4575 4400);
PAINT GREEN (-4575 4400);
DISPLAY INVISIBLE (-4575 4400);
FORCEADD GND..1
(1550 3975);
FORCEPROP 3 LASTPIN (1550 4025) SIG_NAME GND\g
J 0
(1560 4035);
DISPLAY 0.659574 (1560 4035);
PAINT MONO (1560 4035);
DISPLAY INVISIBLE (1560 4035);
FORCEPROP 1 LAST BODY_TYPE PLUMBING
J 0
(1505 3932);
DISPLAY 0.340426 (1505 3932);
PAINT GREEN (1505 3932);
DISPLAY INVISIBLE (1505 3932);
FORCEPROP 1 LAST VOLTAGE 0.0V
J 0
(1505 3932);
DISPLAY 0.340426 (1505 3932);
PAINT SKYBLUE (1505 3932);
DISPLAY INVISIBLE (1505 3932);
FORCEPROP 1 LAST PATH I150
J 0
(1625 3975);
DISPLAY 0.872340 (1625 3975);
PAINT AQUA (1625 3975);
DISPLAY INVISIBLE (1625 3975);
FORCEPROP 1 LAST SIZE 1B
J 0
(1625 3925);
DISPLAY 0.872340 (1625 3925);
PAINT AQUA (1625 3925);
DISPLAY INVISIBLE (1625 3925);
FORCEPROP 2 LAST CDS_LIB mstr_symbols
J 0
(1550 3975);
PAINT MONO (1550 3975);
DISPLAY INVISIBLE (1550 3975);
FORCEPROP 1 LAST HDL_POWER GND
J 0
(1550 4125);
DISPLAY 0.872340 (1550 4125);
PAINT GREEN (1550 4125);
DISPLAY INVISIBLE (1550 4125);
FORCEADD RES..1
(1050 3750);
FORCEPROP 1 LASTPIN (950 3750) $PN 1
J 0
(962 3762);
DISPLAY 0.617021 (962 3762);
PAINT ORANGE (962 3762);
FORCEPROP 1 LAST WATTAGE 1/16W
J 2
(1025 3600);
DISPLAY 0.617021 (1025 3600);
PAINT SKYBLUE (1025 3600);
FORCEPROP 1 LAST VALUE 42.2
J 2
(1025 3650);
DISPLAY 0.617021 (1025 3650);
PAINT SKYBLUE (1025 3650);
FORCEPROP 1 LAST LOCATION R6P2
J 0
(1000 3800);
DISPLAY 0.617021 (1000 3800);
PAINT AQUA (1000 3800);
FORCEPROP 1 LASTPIN (1150 3750) $PN 2
J 0
(1112 3762);
DISPLAY 0.617021 (1112 3762);
PAINT ORANGE (1112 3762);
FORCEPROP 1 LAST TOLERANCE 1.0%
J 0
(1050 3650);
DISPLAY 0.617021 (1050 3650);
PAINT SKYBLUE (1050 3650);
FORCEPROP 1 LAST MATERIAL EMPTY
J 0
(1050 3600);
DISPLAY 0.617021 (1050 3600);
PAINT RED (1050 3600);
FORCEPROP 1 LAST PART_NUMBER G21796-259
J 0
(1200 3750);
DISPLAY 0.617021 (1200 3750);
PAINT BLUE (1200 3750);
FORCEPROP 1 LAST PACK_TYPE 0402
J 0
(1300 3600);
DISPLAY 0.617021 (1300 3600);
PAINT SKYBLUE (1300 3600);
FORCEPROP 2 LAST CDS_LOCATION R6P2
J 0
(1000 3800);
DISPLAY 0.617021 (1000 3800);
PAINT AQUA (1000 3800);
DISPLAY INVISIBLE (1000 3800);
FORCEPROP 1 LAST PATH I151
J 0
(1000 3900);
DISPLAY 0.978723 (1000 3900);
PAINT WHITE (1000 3900);
DISPLAY INVISIBLE (1000 3900);
FORCEPROP 0 LAST ROOM DB1200Z
J 0
(1000 3950);
DISPLAY 1.021277 (1000 3950);
PAINT ORANGE (1000 3950);
DISPLAY INVISIBLE (1000 3950);
FORCEPROP 2 LAST SEC 1
J 0
(1000 3950);
DISPLAY 0.680851 (1000 3950);
PAINT MONO (1000 3950);
DISPLAY INVISIBLE (1000 3950);
FORCEPROP 2 LAST SEC_TYPE 0402
J 0
(1000 3950);
DISPLAY 1.021277 (1000 3950);
PAINT ORANGE (1000 3950);
DISPLAY INVISIBLE (1000 3950);
FORCEPROP 0 LAST BOM_COST SYS_CLOCK
J 0
(1000 4050);
DISPLAY 1.021277 (1000 4050);
PAINT ORANGE (1000 4050);
DISPLAY INVISIBLE (1000 4050);
FORCEPROP 2 LAST CDS_LIB mstr_discrete
J 0
(1050 3750);
PAINT MONO (1050 3750);
DISPLAY INVISIBLE (1050 3750);
FORCEADD GND..1
(1575 3650);
FORCEPROP 3 LASTPIN (1575 3700) SIG_NAME GND\g
J 0
(1585 3710);
DISPLAY 0.659574 (1585 3710);
PAINT MONO (1585 3710);
DISPLAY INVISIBLE (1585 3710);
FORCEPROP 1 LAST BODY_TYPE PLUMBING
J 0
(1530 3607);
DISPLAY 0.340426 (1530 3607);
PAINT GREEN (1530 3607);
DISPLAY INVISIBLE (1530 3607);
FORCEPROP 1 LAST VOLTAGE 0.0V
J 0
(1530 3607);
DISPLAY 0.340426 (1530 3607);
PAINT SKYBLUE (1530 3607);
DISPLAY INVISIBLE (1530 3607);
FORCEPROP 1 LAST SIZE 1B
J 0
(1650 3600);
DISPLAY 0.872340 (1650 3600);
PAINT AQUA (1650 3600);
DISPLAY INVISIBLE (1650 3600);
FORCEPROP 2 LAST CDS_LIB mstr_symbols
J 0
(1575 3650);
PAINT MONO (1575 3650);
DISPLAY INVISIBLE (1575 3650);
FORCEPROP 1 LAST PATH I152
J 0
(1650 3650);
DISPLAY 0.872340 (1650 3650);
PAINT AQUA (1650 3650);
DISPLAY INVISIBLE (1650 3650);
FORCEPROP 1 LAST HDL_POWER GND
J 0
(1575 3800);
DISPLAY 0.872340 (1575 3800);
PAINT GREEN (1575 3800);
DISPLAY INVISIBLE (1575 3800);
FORCEADD RES..1
(1050 3425);
FORCEPROP 1 LASTPIN (950 3425) $PN 1
J 0
(962 3437);
DISPLAY 0.617021 (962 3437);
PAINT ORANGE (962 3437);
FORCEPROP 1 LAST WATTAGE 1/16W
J 2
(1025 3275);
DISPLAY 0.617021 (1025 3275);
PAINT SKYBLUE (1025 3275);
FORCEPROP 1 LAST VALUE 42.2
J 2
(1025 3325);
DISPLAY 0.617021 (1025 3325);
PAINT SKYBLUE (1025 3325);
FORCEPROP 1 LAST LOCATION R6P11
J 0
(1000 3475);
DISPLAY 0.617021 (1000 3475);
PAINT AQUA (1000 3475);
FORCEPROP 1 LAST MATERIAL EMPTY
J 0
(1050 3275);
DISPLAY 0.617021 (1050 3275);
PAINT RED (1050 3275);
FORCEPROP 1 LAST TOLERANCE 1.0%
J 0
(1050 3325);
DISPLAY 0.617021 (1050 3325);
PAINT SKYBLUE (1050 3325);
FORCEPROP 1 LASTPIN (1150 3425) $PN 2
J 0
(1112 3437);
DISPLAY 0.617021 (1112 3437);
PAINT ORANGE (1112 3437);
FORCEPROP 1 LAST PART_NUMBER G21796-259
J 0
(1200 3425);
DISPLAY 0.617021 (1200 3425);
PAINT BLUE (1200 3425);
FORCEPROP 1 LAST PACK_TYPE 0402
J 0
(1300 3275);
DISPLAY 0.617021 (1300 3275);
PAINT SKYBLUE (1300 3275);
FORCEPROP 2 LAST CDS_LOCATION R6P11
J 0
(1000 3475);
DISPLAY 0.617021 (1000 3475);
PAINT AQUA (1000 3475);
DISPLAY INVISIBLE (1000 3475);
FORCEPROP 1 LAST PATH I153
J 0
(1000 3575);
DISPLAY 0.978723 (1000 3575);
PAINT WHITE (1000 3575);
DISPLAY INVISIBLE (1000 3575);
FORCEPROP 0 LAST ROOM DB1200Z
J 0
(1000 3625);
DISPLAY 1.021277 (1000 3625);
PAINT ORANGE (1000 3625);
DISPLAY INVISIBLE (1000 3625);
FORCEPROP 2 LAST SEC 1
J 0
(1000 3625);
DISPLAY 0.680851 (1000 3625);
PAINT MONO (1000 3625);
DISPLAY INVISIBLE (1000 3625);
FORCEPROP 2 LAST SEC_TYPE 0402
J 0
(1000 3625);
DISPLAY 1.021277 (1000 3625);
PAINT ORANGE (1000 3625);
DISPLAY INVISIBLE (1000 3625);
FORCEPROP 0 LAST BOM_COST SYS_CLOCK
J 0
(1000 3725);
DISPLAY 1.021277 (1000 3725);
PAINT ORANGE (1000 3725);
DISPLAY INVISIBLE (1000 3725);
FORCEPROP 2 LAST CDS_LIB mstr_discrete
J 0
(1050 3425);
PAINT MONO (1050 3425);
DISPLAY INVISIBLE (1050 3425);
FORCEADD GND..1
(1575 3325);
FORCEPROP 3 LASTPIN (1575 3375) SIG_NAME GND\g
J 0
(1585 3385);
DISPLAY 0.659574 (1585 3385);
PAINT MONO (1585 3385);
DISPLAY INVISIBLE (1585 3385);
FORCEPROP 1 LAST BODY_TYPE PLUMBING
J 0
(1530 3282);
DISPLAY 0.340426 (1530 3282);
PAINT GREEN (1530 3282);
DISPLAY INVISIBLE (1530 3282);
FORCEPROP 1 LAST VOLTAGE 0.0V
J 0
(1530 3282);
DISPLAY 0.340426 (1530 3282);
PAINT SKYBLUE (1530 3282);
DISPLAY INVISIBLE (1530 3282);
FORCEPROP 1 LAST SIZE 1B
J 0
(1650 3275);
DISPLAY 0.872340 (1650 3275);
PAINT AQUA (1650 3275);
DISPLAY INVISIBLE (1650 3275);
FORCEPROP 2 LAST CDS_LIB mstr_symbols
J 0
(1575 3325);
PAINT MONO (1575 3325);
DISPLAY INVISIBLE (1575 3325);
FORCEPROP 1 LAST PATH I154
J 0
(1650 3325);
DISPLAY 0.872340 (1650 3325);
PAINT AQUA (1650 3325);
DISPLAY INVISIBLE (1650 3325);
FORCEPROP 1 LAST HDL_POWER GND
J 0
(1575 3475);
DISPLAY 0.872340 (1575 3475);
PAINT GREEN (1575 3475);
DISPLAY INVISIBLE (1575 3475);
FORCEADD RES..1
(1075 3100);
FORCEPROP 1 LASTPIN (975 3100) $PN 1
J 0
(987 3112);
DISPLAY 0.617021 (987 3112);
PAINT ORANGE (987 3112);
FORCEPROP 1 LAST WATTAGE 1/16W
J 2
(1050 2950);
DISPLAY 0.617021 (1050 2950);
PAINT SKYBLUE (1050 2950);
FORCEPROP 1 LAST VALUE 42.2
J 2
(1050 3000);
DISPLAY 0.617021 (1050 3000);
PAINT SKYBLUE (1050 3000);
FORCEPROP 1 LAST TOLERANCE 1.0%
J 0
(1075 3000);
DISPLAY 0.617021 (1075 3000);
PAINT SKYBLUE (1075 3000);
FORCEPROP 1 LAST MATERIAL EMPTY
J 0
(1075 2950);
DISPLAY 0.617021 (1075 2950);
PAINT RED (1075 2950);
FORCEPROP 1 LAST PACK_TYPE 0402
J 0
(1325 2950);
DISPLAY 0.617021 (1325 2950);
PAINT SKYBLUE (1325 2950);
FORCEPROP 1 LAST LOCATION R6P9
J 0
(1025 3150);
DISPLAY 0.617021 (1025 3150);
PAINT AQUA (1025 3150);
FORCEPROP 1 LASTPIN (1175 3100) $PN 2
J 0
(1137 3112);
DISPLAY 0.617021 (1137 3112);
PAINT ORANGE (1137 3112);
FORCEPROP 1 LAST PART_NUMBER G21796-259
J 0
(1225 3100);
DISPLAY 0.617021 (1225 3100);
PAINT BLUE (1225 3100);
FORCEPROP 2 LAST CDS_LOCATION R6P9
J 0
(1025 3150);
DISPLAY 0.617021 (1025 3150);
PAINT AQUA (1025 3150);
DISPLAY INVISIBLE (1025 3150);
FORCEPROP 2 LAST CDS_LIB mstr_discrete
J 0
(1075 3100);
PAINT MONO (1075 3100);
DISPLAY INVISIBLE (1075 3100);
FORCEPROP 1 LAST PATH I155
J 0
(1025 3250);
DISPLAY 0.978723 (1025 3250);
PAINT WHITE (1025 3250);
DISPLAY INVISIBLE (1025 3250);
FORCEPROP 0 LAST ROOM DB1200Z
J 0
(1025 3300);
DISPLAY 1.021277 (1025 3300);
PAINT ORANGE (1025 3300);
DISPLAY INVISIBLE (1025 3300);
FORCEPROP 2 LAST SEC 1
J 0
(1025 3300);
DISPLAY 0.680851 (1025 3300);
PAINT MONO (1025 3300);
DISPLAY INVISIBLE (1025 3300);
FORCEPROP 2 LAST SEC_TYPE 0402
J 0
(1025 3300);
DISPLAY 1.021277 (1025 3300);
PAINT ORANGE (1025 3300);
DISPLAY INVISIBLE (1025 3300);
FORCEPROP 0 LAST BOM_COST SYS_CLOCK
J 0
(1025 3400);
DISPLAY 1.021277 (1025 3400);
PAINT ORANGE (1025 3400);
DISPLAY INVISIBLE (1025 3400);
FORCEADD GND..1
(1600 3000);
FORCEPROP 3 LASTPIN (1600 3050) SIG_NAME GND\g
J 0
(1610 3060);
DISPLAY 0.659574 (1610 3060);
PAINT MONO (1610 3060);
DISPLAY INVISIBLE (1610 3060);
FORCEPROP 1 LAST PATH I156
J 0
(1675 3000);
DISPLAY 0.872340 (1675 3000);
PAINT AQUA (1675 3000);
DISPLAY INVISIBLE (1675 3000);
FORCEPROP 1 LAST BODY_TYPE PLUMBING
J 0
(1555 2957);
DISPLAY 0.340426 (1555 2957);
PAINT GREEN (1555 2957);
DISPLAY INVISIBLE (1555 2957);
FORCEPROP 2 LAST CDS_LIB mstr_symbols
J 0
(1600 3000);
PAINT MONO (1600 3000);
DISPLAY INVISIBLE (1600 3000);
FORCEPROP 1 LAST SIZE 1B
J 0
(1675 2950);
DISPLAY 0.872340 (1675 2950);
PAINT AQUA (1675 2950);
DISPLAY INVISIBLE (1675 2950);
FORCEPROP 1 LAST VOLTAGE 0.0V
J 0
(1555 2957);
DISPLAY 0.340426 (1555 2957);
PAINT SKYBLUE (1555 2957);
DISPLAY INVISIBLE (1555 2957);
FORCEPROP 1 LAST HDL_POWER GND
J 0
(1600 3150);
DISPLAY 0.872340 (1600 3150);
PAINT GREEN (1600 3150);
DISPLAY INVISIBLE (1600 3150);
FORCEADD RES..1
(1050 2775);
FORCEPROP 1 LASTPIN (950 2775) $PN 1
J 0
(962 2787);
DISPLAY 0.617021 (962 2787);
PAINT ORANGE (962 2787);
FORCEPROP 1 LAST WATTAGE 1/16W
J 2
(1025 2625);
DISPLAY 0.617021 (1025 2625);
PAINT SKYBLUE (1025 2625);
FORCEPROP 1 LAST VALUE 42.2
J 2
(1025 2675);
DISPLAY 0.617021 (1025 2675);
PAINT SKYBLUE (1025 2675);
FORCEPROP 1 LAST LOCATION R6P13
J 0
(1000 2825);
DISPLAY 0.617021 (1000 2825);
PAINT AQUA (1000 2825);
FORCEPROP 1 LASTPIN (1150 2775) $PN 2
J 0
(1112 2787);
DISPLAY 0.617021 (1112 2787);
PAINT ORANGE (1112 2787);
FORCEPROP 1 LAST TOLERANCE 1.0%
J 0
(1050 2675);
DISPLAY 0.617021 (1050 2675);
PAINT SKYBLUE (1050 2675);
FORCEPROP 1 LAST MATERIAL EMPTY
J 0
(1050 2625);
DISPLAY 0.617021 (1050 2625);
PAINT RED (1050 2625);
FORCEPROP 1 LAST PART_NUMBER G21796-259
J 0
(1200 2775);
DISPLAY 0.617021 (1200 2775);
PAINT BLUE (1200 2775);
FORCEPROP 1 LAST PACK_TYPE 0402
J 0
(1300 2625);
DISPLAY 0.617021 (1300 2625);
PAINT SKYBLUE (1300 2625);
FORCEPROP 2 LAST SEC_TYPE 0402
J 0
(1000 2975);
DISPLAY 1.021277 (1000 2975);
PAINT ORANGE (1000 2975);
DISPLAY INVISIBLE (1000 2975);
FORCEPROP 2 LAST SEC 1
J 0
(1000 2975);
DISPLAY 0.680851 (1000 2975);
PAINT MONO (1000 2975);
DISPLAY INVISIBLE (1000 2975);
FORCEPROP 2 LAST CDS_LOCATION R6P13
J 0
(1000 2825);
DISPLAY 0.617021 (1000 2825);
PAINT AQUA (1000 2825);
DISPLAY INVISIBLE (1000 2825);
FORCEPROP 1 LAST PATH I157
J 0
(1000 2925);
DISPLAY 0.978723 (1000 2925);
PAINT WHITE (1000 2925);
DISPLAY INVISIBLE (1000 2925);
FORCEPROP 0 LAST ROOM DB1200Z
J 0
(1000 2975);
DISPLAY 1.021277 (1000 2975);
PAINT ORANGE (1000 2975);
DISPLAY INVISIBLE (1000 2975);
FORCEPROP 0 LAST BOM_COST SYS_CLOCK
J 0
(1000 3075);
DISPLAY 1.021277 (1000 3075);
PAINT ORANGE (1000 3075);
DISPLAY INVISIBLE (1000 3075);
FORCEPROP 2 LAST CDS_LIB mstr_discrete
J 0
(1050 2775);
PAINT MONO (1050 2775);
DISPLAY INVISIBLE (1050 2775);
FORCEADD GND..1
(1575 2675);
FORCEPROP 3 LASTPIN (1575 2725) SIG_NAME GND\g
J 0
(1585 2735);
DISPLAY 0.659574 (1585 2735);
PAINT MONO (1585 2735);
DISPLAY INVISIBLE (1585 2735);
FORCEPROP 1 LAST BODY_TYPE PLUMBING
J 0
(1530 2632);
DISPLAY 0.340426 (1530 2632);
PAINT GREEN (1530 2632);
DISPLAY INVISIBLE (1530 2632);
FORCEPROP 1 LAST VOLTAGE 0.0V
J 0
(1530 2632);
DISPLAY 0.340426 (1530 2632);
PAINT SKYBLUE (1530 2632);
DISPLAY INVISIBLE (1530 2632);
FORCEPROP 1 LAST PATH I158
J 0
(1650 2675);
DISPLAY 0.872340 (1650 2675);
PAINT AQUA (1650 2675);
DISPLAY INVISIBLE (1650 2675);
FORCEPROP 1 LAST SIZE 1B
J 0
(1650 2625);
DISPLAY 0.872340 (1650 2625);
PAINT AQUA (1650 2625);
DISPLAY INVISIBLE (1650 2625);
FORCEPROP 2 LAST CDS_LIB mstr_symbols
J 0
(1575 2675);
PAINT MONO (1575 2675);
DISPLAY INVISIBLE (1575 2675);
FORCEPROP 1 LAST HDL_POWER GND
J 0
(1575 2825);
DISPLAY 0.872340 (1575 2825);
PAINT GREEN (1575 2825);
DISPLAY INVISIBLE (1575 2825);
FORCEADD RES..1
(1050 2450);
FORCEPROP 1 LASTPIN (950 2450) $PN 1
J 0
(962 2462);
DISPLAY 0.617021 (962 2462);
PAINT ORANGE (962 2462);
FORCEPROP 1 LAST WATTAGE 1/16W
J 2
(1025 2300);
DISPLAY 0.617021 (1025 2300);
PAINT SKYBLUE (1025 2300);
FORCEPROP 1 LAST VALUE 42.2
J 2
(1025 2350);
DISPLAY 0.617021 (1025 2350);
PAINT SKYBLUE (1025 2350);
FORCEPROP 1 LAST LOCATION R6P12
J 0
(1000 2500);
DISPLAY 0.617021 (1000 2500);
PAINT AQUA (1000 2500);
FORCEPROP 1 LAST MATERIAL EMPTY
J 0
(1050 2300);
DISPLAY 0.617021 (1050 2300);
PAINT RED (1050 2300);
FORCEPROP 1 LASTPIN (1150 2450) $PN 2
J 0
(1112 2462);
DISPLAY 0.617021 (1112 2462);
PAINT ORANGE (1112 2462);
FORCEPROP 1 LAST TOLERANCE 1.0%
J 0
(1050 2350);
DISPLAY 0.617021 (1050 2350);
PAINT SKYBLUE (1050 2350);
FORCEPROP 1 LAST PART_NUMBER G21796-259
J 0
(1200 2450);
DISPLAY 0.617021 (1200 2450);
PAINT BLUE (1200 2450);
FORCEPROP 1 LAST PACK_TYPE 0402
J 0
(1300 2300);
DISPLAY 0.617021 (1300 2300);
PAINT SKYBLUE (1300 2300);
FORCEPROP 2 LAST CDS_LOCATION R6P12
J 0
(1000 2500);
DISPLAY 0.617021 (1000 2500);
PAINT AQUA (1000 2500);
DISPLAY INVISIBLE (1000 2500);
FORCEPROP 1 LAST PATH I159
J 0
(1000 2600);
DISPLAY 0.978723 (1000 2600);
PAINT WHITE (1000 2600);
DISPLAY INVISIBLE (1000 2600);
FORCEPROP 2 LAST SEC 1
J 0
(1000 2650);
DISPLAY 0.680851 (1000 2650);
PAINT MONO (1000 2650);
DISPLAY INVISIBLE (1000 2650);
FORCEPROP 0 LAST ROOM DB1200Z
J 0
(1000 2650);
DISPLAY 1.021277 (1000 2650);
PAINT ORANGE (1000 2650);
DISPLAY INVISIBLE (1000 2650);
FORCEPROP 2 LAST SEC_TYPE 0402
J 0
(1000 2650);
DISPLAY 1.021277 (1000 2650);
PAINT ORANGE (1000 2650);
DISPLAY INVISIBLE (1000 2650);
FORCEPROP 0 LAST BOM_COST SYS_CLOCK
J 0
(1000 2750);
DISPLAY 1.021277 (1000 2750);
PAINT ORANGE (1000 2750);
DISPLAY INVISIBLE (1000 2750);
FORCEPROP 2 LAST CDS_LIB mstr_discrete
J 0
(1050 2450);
PAINT MONO (1050 2450);
DISPLAY INVISIBLE (1050 2450);
FORCEADD OFFPAGE..2
(-2225 4175);
FORCEPROP 2 LAST $XR0 56 
J 0
(-2036 4175);
DISPLAY 0.638298 (-2036 4175);
PAINT MONO (-2036 4175);
FORCEPROP 1 LAST OFFPAGE TRUE
J 0
(-1900 4050);
DISPLAY 0.872340 (-1900 4050);
PAINT GREEN (-1900 4050);
DISPLAY INVISIBLE (-1900 4050);
FORCEPROP 1 LAST COMMENT_BODY TRUE
J 0
(-2270 4080);
DISPLAY 0.872340 (-2270 4080);
PAINT GREEN (-2270 4080);
DISPLAY INVISIBLE (-2270 4080);
FORCEPROP 2 LAST CDS_LIB mstr_standard
J 0
(-2225 4175);
PAINT ORANGE (-2225 4175);
DISPLAY INVISIBLE (-2225 4175);
FORCEPROP 2 LAST PATH I16
J 0
(-2050 4250);
DISPLAY 1.021277 (-2050 4250);
PAINT ORANGE (-2050 4250);
DISPLAY INVISIBLE (-2050 4250);
FORCEADD GND..1
(1575 2350);
FORCEPROP 3 LASTPIN (1575 2400) SIG_NAME GND\g
J 0
(1585 2410);
DISPLAY 0.659574 (1585 2410);
PAINT MONO (1585 2410);
DISPLAY INVISIBLE (1585 2410);
FORCEPROP 1 LAST BODY_TYPE PLUMBING
J 0
(1530 2307);
DISPLAY 0.340426 (1530 2307);
PAINT GREEN (1530 2307);
DISPLAY INVISIBLE (1530 2307);
FORCEPROP 1 LAST VOLTAGE 0.0V
J 0
(1530 2307);
DISPLAY 0.340426 (1530 2307);
PAINT SKYBLUE (1530 2307);
DISPLAY INVISIBLE (1530 2307);
FORCEPROP 1 LAST SIZE 1B
J 0
(1650 2300);
DISPLAY 0.872340 (1650 2300);
PAINT AQUA (1650 2300);
DISPLAY INVISIBLE (1650 2300);
FORCEPROP 2 LAST CDS_LIB mstr_symbols
J 0
(1575 2350);
PAINT MONO (1575 2350);
DISPLAY INVISIBLE (1575 2350);
FORCEPROP 1 LAST PATH I160
J 0
(1650 2350);
DISPLAY 0.872340 (1650 2350);
PAINT AQUA (1650 2350);
DISPLAY INVISIBLE (1650 2350);
FORCEPROP 1 LAST HDL_POWER GND
J 0
(1575 2500);
DISPLAY 0.872340 (1575 2500);
PAINT GREEN (1575 2500);
DISPLAY INVISIBLE (1575 2500);
FORCEADD RES..1
(1050 2125);
FORCEPROP 1 LAST WATTAGE 1/16W
J 2
(1025 1975);
DISPLAY 0.617021 (1025 1975);
PAINT SKYBLUE (1025 1975);
FORCEPROP 1 LAST MATERIAL EMPTY
J 0
(1050 1975);
DISPLAY 0.617021 (1050 1975);
PAINT RED (1050 1975);
FORCEPROP 1 LAST PACK_TYPE 0402
J 0
(1300 1975);
DISPLAY 0.617021 (1300 1975);
PAINT SKYBLUE (1300 1975);
FORCEPROP 1 LAST TOLERANCE 1.0%
J 0
(1050 2025);
DISPLAY 0.617021 (1050 2025);
PAINT SKYBLUE (1050 2025);
FORCEPROP 1 LAST VALUE 42.2
J 2
(1025 2025);
DISPLAY 0.617021 (1025 2025);
PAINT SKYBLUE (1025 2025);
FORCEPROP 1 LASTPIN (950 2125) $PN 1
J 0
(962 2137);
DISPLAY 0.617021 (962 2137);
PAINT ORANGE (962 2137);
FORCEPROP 1 LAST LOCATION R4D24
J 0
(1000 2175);
DISPLAY 0.617021 (1000 2175);
PAINT AQUA (1000 2175);
FORCEPROP 1 LASTPIN (1150 2125) $PN 2
J 0
(1112 2137);
DISPLAY 0.617021 (1112 2137);
PAINT ORANGE (1112 2137);
FORCEPROP 1 LAST PART_NUMBER G21796-259
J 0
(1200 2125);
DISPLAY 0.617021 (1200 2125);
PAINT BLUE (1200 2125);
FORCEPROP 2 LAST CDS_LOCATION R4D24
J 0
(1000 2175);
DISPLAY 0.617021 (1000 2175);
PAINT AQUA (1000 2175);
DISPLAY INVISIBLE (1000 2175);
FORCEPROP 1 LAST PATH I161
J 0
(1000 2275);
DISPLAY 0.978723 (1000 2275);
PAINT WHITE (1000 2275);
DISPLAY INVISIBLE (1000 2275);
FORCEPROP 0 LAST ROOM DB1200Z
J 0
(1000 2325);
DISPLAY 1.021277 (1000 2325);
PAINT ORANGE (1000 2325);
DISPLAY INVISIBLE (1000 2325);
FORCEPROP 2 LAST SEC 1
J 0
(1000 2325);
DISPLAY 0.680851 (1000 2325);
PAINT MONO (1000 2325);
DISPLAY INVISIBLE (1000 2325);
FORCEPROP 2 LAST SEC_TYPE 0402
J 0
(1000 2325);
DISPLAY 1.021277 (1000 2325);
PAINT ORANGE (1000 2325);
DISPLAY INVISIBLE (1000 2325);
FORCEPROP 0 LAST BOM_COST SYS_CLOCK
J 0
(1000 2425);
DISPLAY 1.021277 (1000 2425);
PAINT ORANGE (1000 2425);
DISPLAY INVISIBLE (1000 2425);
FORCEPROP 2 LAST CDS_LIB mstr_discrete
J 0
(1050 2125);
PAINT MONO (1050 2125);
DISPLAY INVISIBLE (1050 2125);
FORCEADD GND..1
(1575 2025);
FORCEPROP 3 LASTPIN (1575 2075) SIG_NAME GND\g
J 0
(1585 2085);
DISPLAY 0.659574 (1585 2085);
PAINT MONO (1585 2085);
DISPLAY INVISIBLE (1585 2085);
FORCEPROP 1 LAST BODY_TYPE PLUMBING
J 0
(1530 1982);
DISPLAY 0.340426 (1530 1982);
PAINT GREEN (1530 1982);
DISPLAY INVISIBLE (1530 1982);
FORCEPROP 1 LAST VOLTAGE 0.0V
J 0
(1530 1982);
DISPLAY 0.340426 (1530 1982);
PAINT SKYBLUE (1530 1982);
DISPLAY INVISIBLE (1530 1982);
FORCEPROP 1 LAST SIZE 1B
J 0
(1650 1975);
DISPLAY 0.872340 (1650 1975);
PAINT AQUA (1650 1975);
DISPLAY INVISIBLE (1650 1975);
FORCEPROP 1 LAST PATH I162
J 0
(1650 2025);
DISPLAY 0.872340 (1650 2025);
PAINT AQUA (1650 2025);
DISPLAY INVISIBLE (1650 2025);
FORCEPROP 2 LAST CDS_LIB mstr_symbols
J 0
(1575 2025);
PAINT MONO (1575 2025);
DISPLAY INVISIBLE (1575 2025);
FORCEPROP 1 LAST HDL_POWER GND
J 0
(1575 2175);
DISPLAY 0.872340 (1575 2175);
PAINT GREEN (1575 2175);
DISPLAY INVISIBLE (1575 2175);
FORCEADD RES..1
(1050 1800);
FORCEPROP 1 LASTPIN (950 1800) $PN 1
J 0
(962 1812);
DISPLAY 0.617021 (962 1812);
PAINT ORANGE (962 1812);
FORCEPROP 1 LAST WATTAGE 1/16W
J 2
(1025 1650);
DISPLAY 0.617021 (1025 1650);
PAINT SKYBLUE (1025 1650);
FORCEPROP 1 LAST VALUE 42.2
J 2
(1025 1700);
DISPLAY 0.617021 (1025 1700);
PAINT SKYBLUE (1025 1700);
FORCEPROP 1 LAST LOCATION R4D18
J 0
(1000 1850);
DISPLAY 0.617021 (1000 1850);
PAINT AQUA (1000 1850);
FORCEPROP 1 LAST TOLERANCE 1.0%
J 0
(1050 1700);
DISPLAY 0.617021 (1050 1700);
PAINT SKYBLUE (1050 1700);
FORCEPROP 1 LAST MATERIAL EMPTY
J 0
(1050 1650);
DISPLAY 0.617021 (1050 1650);
PAINT RED (1050 1650);
FORCEPROP 1 LASTPIN (1150 1800) $PN 2
J 0
(1112 1812);
DISPLAY 0.617021 (1112 1812);
PAINT ORANGE (1112 1812);
FORCEPROP 1 LAST PART_NUMBER G21796-259
J 0
(1200 1800);
DISPLAY 0.617021 (1200 1800);
PAINT BLUE (1200 1800);
FORCEPROP 1 LAST PACK_TYPE 0402
J 0
(1300 1650);
DISPLAY 0.617021 (1300 1650);
PAINT SKYBLUE (1300 1650);
FORCEPROP 2 LAST CDS_LOCATION R4D18
J 0
(1000 1850);
DISPLAY 0.617021 (1000 1850);
PAINT AQUA (1000 1850);
DISPLAY INVISIBLE (1000 1850);
FORCEPROP 0 LAST ROOM DB1200Z
J 0
(1000 2000);
DISPLAY 1.021277 (1000 2000);
PAINT ORANGE (1000 2000);
DISPLAY INVISIBLE (1000 2000);
FORCEPROP 1 LAST PATH I163
J 0
(1000 1950);
DISPLAY 0.978723 (1000 1950);
PAINT WHITE (1000 1950);
DISPLAY INVISIBLE (1000 1950);
FORCEPROP 2 LAST SEC_TYPE 0402
J 0
(1000 2000);
DISPLAY 1.021277 (1000 2000);
PAINT ORANGE (1000 2000);
DISPLAY INVISIBLE (1000 2000);
FORCEPROP 2 LAST SEC 1
J 0
(1000 2000);
DISPLAY 0.680851 (1000 2000);
PAINT MONO (1000 2000);
DISPLAY INVISIBLE (1000 2000);
FORCEPROP 2 LAST CDS_LIB mstr_discrete
J 0
(1050 1800);
PAINT MONO (1050 1800);
DISPLAY INVISIBLE (1050 1800);
FORCEPROP 0 LAST BOM_COST SYS_CLOCK
J 0
(1000 2100);
DISPLAY 1.021277 (1000 2100);
PAINT ORANGE (1000 2100);
DISPLAY INVISIBLE (1000 2100);
FORCEADD GND..1
(1575 1700);
FORCEPROP 3 LASTPIN (1575 1750) SIG_NAME GND\g
J 0
(1585 1760);
DISPLAY 0.659574 (1585 1760);
PAINT MONO (1585 1760);
DISPLAY INVISIBLE (1585 1760);
FORCEPROP 1 LAST BODY_TYPE PLUMBING
J 0
(1530 1657);
DISPLAY 0.340426 (1530 1657);
PAINT GREEN (1530 1657);
DISPLAY INVISIBLE (1530 1657);
FORCEPROP 1 LAST VOLTAGE 0.0V
J 0
(1530 1657);
DISPLAY 0.340426 (1530 1657);
PAINT SKYBLUE (1530 1657);
DISPLAY INVISIBLE (1530 1657);
FORCEPROP 2 LAST CDS_LIB mstr_symbols
J 0
(1575 1700);
PAINT MONO (1575 1700);
DISPLAY INVISIBLE (1575 1700);
FORCEPROP 1 LAST SIZE 1B
J 0
(1650 1650);
DISPLAY 0.872340 (1650 1650);
PAINT AQUA (1650 1650);
DISPLAY INVISIBLE (1650 1650);
FORCEPROP 1 LAST PATH I164
J 0
(1650 1700);
DISPLAY 0.872340 (1650 1700);
PAINT AQUA (1650 1700);
DISPLAY INVISIBLE (1650 1700);
FORCEPROP 1 LAST HDL_POWER GND
J 0
(1575 1850);
DISPLAY 0.872340 (1575 1850);
PAINT GREEN (1575 1850);
DISPLAY INVISIBLE (1575 1850);
FORCEADD RES..1
(1050 1475);
FORCEPROP 1 LASTPIN (950 1475) $PN 1
J 0
(962 1487);
DISPLAY 0.617021 (962 1487);
PAINT ORANGE (962 1487);
FORCEPROP 1 LAST WATTAGE 1/16W
J 2
(1025 1325);
DISPLAY 0.617021 (1025 1325);
PAINT SKYBLUE (1025 1325);
FORCEPROP 1 LAST VALUE 42.2
J 2
(1025 1375);
DISPLAY 0.617021 (1025 1375);
PAINT SKYBLUE (1025 1375);
FORCEPROP 1 LAST LOCATION R6P17
J 0
(1000 1525);
DISPLAY 0.617021 (1000 1525);
PAINT AQUA (1000 1525);
FORCEPROP 1 LASTPIN (1150 1475) $PN 2
J 0
(1112 1487);
DISPLAY 0.617021 (1112 1487);
PAINT ORANGE (1112 1487);
FORCEPROP 1 LAST TOLERANCE 1.0%
J 0
(1050 1375);
DISPLAY 0.617021 (1050 1375);
PAINT SKYBLUE (1050 1375);
FORCEPROP 1 LAST MATERIAL EMPTY
J 0
(1050 1325);
DISPLAY 0.617021 (1050 1325);
PAINT RED (1050 1325);
FORCEPROP 1 LAST PART_NUMBER G21796-259
J 0
(1200 1475);
DISPLAY 0.617021 (1200 1475);
PAINT BLUE (1200 1475);
FORCEPROP 1 LAST PACK_TYPE 0402
J 0
(1300 1325);
DISPLAY 0.617021 (1300 1325);
PAINT SKYBLUE (1300 1325);
FORCEPROP 2 LAST CDS_LOCATION R6P17
J 0
(1000 1525);
DISPLAY 0.617021 (1000 1525);
PAINT AQUA (1000 1525);
DISPLAY INVISIBLE (1000 1525);
FORCEPROP 1 LAST PATH I165
J 0
(1000 1625);
DISPLAY 0.978723 (1000 1625);
PAINT WHITE (1000 1625);
DISPLAY INVISIBLE (1000 1625);
FORCEPROP 0 LAST ROOM DB1200Z
J 0
(1000 1675);
DISPLAY 1.021277 (1000 1675);
PAINT ORANGE (1000 1675);
DISPLAY INVISIBLE (1000 1675);
FORCEPROP 2 LAST SEC 1
J 0
(1000 1675);
DISPLAY 0.680851 (1000 1675);
PAINT MONO (1000 1675);
DISPLAY INVISIBLE (1000 1675);
FORCEPROP 2 LAST SEC_TYPE 0402
J 0
(1000 1675);
DISPLAY 1.021277 (1000 1675);
PAINT ORANGE (1000 1675);
DISPLAY INVISIBLE (1000 1675);
FORCEPROP 0 LAST BOM_COST SYS_CLOCK
J 0
(1000 1775);
DISPLAY 1.021277 (1000 1775);
PAINT ORANGE (1000 1775);
DISPLAY INVISIBLE (1000 1775);
FORCEPROP 2 LAST CDS_LIB mstr_discrete
J 0
(1050 1475);
PAINT MONO (1050 1475);
DISPLAY INVISIBLE (1050 1475);
FORCEADD GND..1
(1575 1375);
FORCEPROP 3 LASTPIN (1575 1425) SIG_NAME GND\g
J 0
(1585 1435);
DISPLAY 0.659574 (1585 1435);
PAINT MONO (1585 1435);
DISPLAY INVISIBLE (1585 1435);
FORCEPROP 1 LAST BODY_TYPE PLUMBING
J 0
(1530 1332);
DISPLAY 0.340426 (1530 1332);
PAINT GREEN (1530 1332);
DISPLAY INVISIBLE (1530 1332);
FORCEPROP 1 LAST VOLTAGE 0.0V
J 0
(1530 1332);
DISPLAY 0.340426 (1530 1332);
PAINT SKYBLUE (1530 1332);
DISPLAY INVISIBLE (1530 1332);
FORCEPROP 1 LAST PATH I166
J 0
(1650 1375);
DISPLAY 0.872340 (1650 1375);
PAINT AQUA (1650 1375);
DISPLAY INVISIBLE (1650 1375);
FORCEPROP 1 LAST SIZE 1B
J 0
(1650 1325);
DISPLAY 0.872340 (1650 1325);
PAINT AQUA (1650 1325);
DISPLAY INVISIBLE (1650 1325);
FORCEPROP 2 LAST CDS_LIB mstr_symbols
J 0
(1575 1375);
PAINT MONO (1575 1375);
DISPLAY INVISIBLE (1575 1375);
FORCEPROP 1 LAST HDL_POWER GND
J 0
(1575 1525);
DISPLAY 0.872340 (1575 1525);
PAINT GREEN (1575 1525);
DISPLAY INVISIBLE (1575 1525);
FORCEADD RES..1
(1050 1150);
FORCEPROP 1 LASTPIN (950 1150) $PN 1
J 0
(962 1162);
DISPLAY 0.617021 (962 1162);
PAINT ORANGE (962 1162);
FORCEPROP 1 LAST WATTAGE 1/16W
J 2
(1025 1000);
DISPLAY 0.617021 (1025 1000);
PAINT SKYBLUE (1025 1000);
FORCEPROP 1 LAST VALUE 42.2
J 2
(1025 1050);
DISPLAY 0.617021 (1025 1050);
PAINT SKYBLUE (1025 1050);
FORCEPROP 1 LAST LOCATION R6P15
J 0
(1000 1200);
DISPLAY 0.617021 (1000 1200);
PAINT AQUA (1000 1200);
FORCEPROP 1 LAST PACK_TYPE 0402
J 0
(1300 1000);
DISPLAY 0.617021 (1300 1000);
PAINT SKYBLUE (1300 1000);
FORCEPROP 1 LAST MATERIAL EMPTY
J 0
(1050 1000);
DISPLAY 0.617021 (1050 1000);
PAINT RED (1050 1000);
FORCEPROP 1 LASTPIN (1150 1150) $PN 2
J 0
(1112 1162);
DISPLAY 0.617021 (1112 1162);
PAINT ORANGE (1112 1162);
FORCEPROP 1 LAST TOLERANCE 1.0%
J 0
(1050 1050);
DISPLAY 0.617021 (1050 1050);
PAINT SKYBLUE (1050 1050);
FORCEPROP 1 LAST PART_NUMBER G21796-259
J 0
(1200 1150);
DISPLAY 0.617021 (1200 1150);
PAINT BLUE (1200 1150);
FORCEPROP 2 LAST CDS_LOCATION R6P15
J 0
(1000 1200);
DISPLAY 0.617021 (1000 1200);
PAINT AQUA (1000 1200);
DISPLAY INVISIBLE (1000 1200);
FORCEPROP 0 LAST ROOM DB1200Z
J 0
(1000 1350);
DISPLAY 1.021277 (1000 1350);
PAINT ORANGE (1000 1350);
DISPLAY INVISIBLE (1000 1350);
FORCEPROP 1 LAST PATH I167
J 0
(1000 1300);
DISPLAY 0.978723 (1000 1300);
PAINT WHITE (1000 1300);
DISPLAY INVISIBLE (1000 1300);
FORCEPROP 2 LAST SEC 1
J 0
(1000 1350);
DISPLAY 0.680851 (1000 1350);
PAINT MONO (1000 1350);
DISPLAY INVISIBLE (1000 1350);
FORCEPROP 2 LAST SEC_TYPE 0402
J 0
(1000 1350);
DISPLAY 1.021277 (1000 1350);
PAINT ORANGE (1000 1350);
DISPLAY INVISIBLE (1000 1350);
FORCEPROP 0 LAST BOM_COST SYS_CLOCK
J 0
(1000 1450);
DISPLAY 1.021277 (1000 1450);
PAINT ORANGE (1000 1450);
DISPLAY INVISIBLE (1000 1450);
FORCEPROP 2 LAST CDS_LIB mstr_discrete
J 0
(1050 1150);
PAINT MONO (1050 1150);
DISPLAY INVISIBLE (1050 1150);
FORCEADD GND..1
(1575 1050);
FORCEPROP 3 LASTPIN (1575 1100) SIG_NAME GND\g
J 0
(1585 1110);
DISPLAY 0.659574 (1585 1110);
PAINT MONO (1585 1110);
DISPLAY INVISIBLE (1585 1110);
FORCEPROP 1 LAST BODY_TYPE PLUMBING
J 0
(1530 1007);
DISPLAY 0.340426 (1530 1007);
PAINT GREEN (1530 1007);
DISPLAY INVISIBLE (1530 1007);
FORCEPROP 1 LAST VOLTAGE 0.0V
J 0
(1530 1007);
DISPLAY 0.340426 (1530 1007);
PAINT SKYBLUE (1530 1007);
DISPLAY INVISIBLE (1530 1007);
FORCEPROP 1 LAST SIZE 1B
J 0
(1650 1000);
DISPLAY 0.872340 (1650 1000);
PAINT AQUA (1650 1000);
DISPLAY INVISIBLE (1650 1000);
FORCEPROP 1 LAST HDL_POWER GND
J 0
(1575 1200);
DISPLAY 0.872340 (1575 1200);
PAINT GREEN (1575 1200);
DISPLAY INVISIBLE (1575 1200);
FORCEPROP 2 LAST CDS_LIB mstr_symbols
J 0
(1575 1050);
PAINT MONO (1575 1050);
DISPLAY INVISIBLE (1575 1050);
FORCEPROP 1 LAST PATH I168
J 0
(1650 1050);
DISPLAY 0.872340 (1650 1050);
PAINT AQUA (1650 1050);
DISPLAY INVISIBLE (1650 1050);
FORCEADD GND..1
(-2775 4325);
FORCEPROP 3 LASTPIN (-2775 4375) SIG_NAME GND\g
J 0
(-2765 4385);
DISPLAY 0.659574 (-2765 4385);
PAINT MONO (-2765 4385);
DISPLAY INVISIBLE (-2765 4385);
FORCEPROP 1 LAST VOLTAGE 0.0V
J 0
(-2820 4282);
DISPLAY 0.340426 (-2820 4282);
PAINT SKYBLUE (-2820 4282);
DISPLAY INVISIBLE (-2820 4282);
FORCEPROP 1 LAST BODY_TYPE PLUMBING
J 0
(-2820 4282);
DISPLAY 0.340426 (-2820 4282);
PAINT GREEN (-2820 4282);
DISPLAY INVISIBLE (-2820 4282);
FORCEPROP 1 LAST SIZE 1B
J 0
(-2700 4275);
DISPLAY 0.872340 (-2700 4275);
PAINT AQUA (-2700 4275);
DISPLAY INVISIBLE (-2700 4275);
FORCEPROP 1 LAST PATH I169
J 0
(-2700 4325);
DISPLAY 0.872340 (-2700 4325);
PAINT AQUA (-2700 4325);
DISPLAY INVISIBLE (-2700 4325);
FORCEPROP 2 LAST CDS_LIB mstr_symbols
J 0
(-2775 4325);
PAINT ORANGE (-2775 4325);
DISPLAY INVISIBLE (-2775 4325);
FORCEPROP 1 LAST HDL_POWER GND
J 0
(-2775 4475);
DISPLAY 0.872340 (-2775 4475);
PAINT GREEN (-2775 4475);
DISPLAY INVISIBLE (-2775 4475);
FORCEADD GND..1
(-2800 4700);
FORCEPROP 3 LASTPIN (-2800 4750) SIG_NAME GND\g
J 0
(-2790 4760);
DISPLAY 0.659574 (-2790 4760);
PAINT MONO (-2790 4760);
DISPLAY INVISIBLE (-2790 4760);
FORCEPROP 1 LAST BODY_TYPE PLUMBING
J 0
(-2845 4657);
DISPLAY 0.340426 (-2845 4657);
PAINT GREEN (-2845 4657);
DISPLAY INVISIBLE (-2845 4657);
FORCEPROP 1 LAST VOLTAGE 0.0V
J 0
(-2845 4657);
DISPLAY 0.340426 (-2845 4657);
PAINT SKYBLUE (-2845 4657);
DISPLAY INVISIBLE (-2845 4657);
FORCEPROP 1 LAST SIZE 1B
J 0
(-2725 4650);
DISPLAY 0.872340 (-2725 4650);
PAINT AQUA (-2725 4650);
DISPLAY INVISIBLE (-2725 4650);
FORCEPROP 2 LAST CDS_LIB mstr_symbols
J 0
(-2800 4700);
PAINT ORANGE (-2800 4700);
DISPLAY INVISIBLE (-2800 4700);
FORCEPROP 1 LAST HDL_POWER GND
J 0
(-2800 4850);
DISPLAY 0.872340 (-2800 4850);
PAINT GREEN (-2800 4850);
DISPLAY INVISIBLE (-2800 4850);
FORCEPROP 1 LAST PATH I170
J 0
(-2725 4700);
DISPLAY 0.872340 (-2725 4700);
PAINT AQUA (-2725 4700);
DISPLAY INVISIBLE (-2725 4700);
FORCEADD RES..1
(-3925 4175);
FORCEPROP 1 LAST VALUE 27.4
J 2
(-4000 4125);
DISPLAY 0.617021 (-4000 4125);
PAINT SKYBLUE (-4000 4125);
FORCEPROP 1 LAST WATTAGE 1/16W
J 2
(-3950 4075);
DISPLAY 0.617021 (-3950 4075);
PAINT SKYBLUE (-3950 4075);
FORCEPROP 1 LAST PACK_TYPE 0402
J 0
(-3850 4075);
DISPLAY 0.617021 (-3850 4075);
PAINT SKYBLUE (-3850 4075);
FORCEPROP 1 LAST TOLERANCE 1%
J 0
(-3925 4075);
DISPLAY 0.617021 (-3925 4075);
PAINT SKYBLUE (-3925 4075);
FORCEPROP 1 LASTPIN (-4025 4175) $PN 1
J 0
(-4013 4187);
DISPLAY 0.617021 (-4013 4187);
PAINT ORANGE (-4013 4187);
FORCEPROP 1 LASTPIN (-3825 4175) $PN 2
J 0
(-3863 4187);
DISPLAY 0.617021 (-3863 4187);
PAINT ORANGE (-3863 4187);
FORCEPROP 1 LAST MATERIAL CHIP
J 0
(-3875 4125);
DISPLAY 0.617021 (-3875 4125);
PAINT SKYBLUE (-3875 4125);
FORCEPROP 1 LAST LOCATION R4D19
J 0
(-3975 4225);
DISPLAY 0.617021 (-3975 4225);
PAINT AQUA (-3975 4225);
FORCEPROP 1 LAST PART_NUMBER G21796-182
J 0
(-3800 4175);
DISPLAY 0.617021 (-3800 4175);
PAINT BLUE (-3800 4175);
FORCEPROP 2 LAST CDS_LOCATION R4D19
J 0
(-3975 4225);
DISPLAY 0.617021 (-3975 4225);
PAINT AQUA (-3975 4225);
DISPLAY INVISIBLE (-3975 4225);
FORCEPROP 2 LAST CDS_LIB mstr_discrete
J 0
(-3925 4175);
PAINT ORANGE (-3925 4175);
DISPLAY INVISIBLE (-3925 4175);
FORCEPROP 0 LAST ROOM DB1200Z
J 0
(-3975 4325);
DISPLAY 1.021277 (-3975 4325);
PAINT ORANGE (-3975 4325);
DISPLAY INVISIBLE (-3975 4325);
FORCEPROP 1 LAST PATH I19
J 0
(-3975 4325);
DISPLAY 0.978723 (-3975 4325);
PAINT WHITE (-3975 4325);
DISPLAY INVISIBLE (-3975 4325);
FORCEPROP 0 LAST BOM_COST SYS_CLOCK
J 0
(-3975 4425);
DISPLAY 1.021277 (-3975 4425);
PAINT ORANGE (-3975 4425);
DISPLAY INVISIBLE (-3975 4425);
FORCEPROP 2 LAST SEC_TYPE 0402
J 0
(-3975 4375);
DISPLAY 1.021277 (-3975 4375);
PAINT ORANGE (-3975 4375);
DISPLAY INVISIBLE (-3975 4375);
FORCEPROP 2 LAST SEC 1
J 0
(-3975 4375);
DISPLAY 0.680851 (-3975 4375);
PAINT MONO (-3975 4375);
DISPLAY INVISIBLE (-3975 4375);
FORCEADD OFFPAGE..1
(-4900 4175);
FORCEPROP 2 LAST $XR0 102 
J 0
(-5152 4175);
DISPLAY 0.638298 (-5152 4175);
PAINT MONO (-5152 4175);
FORCEPROP 1 LAST OFFPAGE TRUE
J 0
(-4575 4050);
DISPLAY 0.872340 (-4575 4050);
PAINT GREEN (-4575 4050);
DISPLAY INVISIBLE (-4575 4050);
FORCEPROP 1 LAST COMMENT_BODY TRUE
J 0
(-4775 4075);
DISPLAY 0.872340 (-4775 4075);
PAINT GREEN (-4775 4075);
DISPLAY INVISIBLE (-4775 4075);
FORCEPROP 2 LAST CDS_LIB mstr_standard
J 0
(-4900 4175);
PAINT ORANGE (-4900 4175);
DISPLAY INVISIBLE (-4900 4175);
FORCEPROP 2 LAST PATH I20
J 0
(-4850 4250);
DISPLAY 1.021277 (-4850 4250);
PAINT ORANGE (-4850 4250);
DISPLAY INVISIBLE (-4850 4250);
FORCEADD OFFPAGE..2
(-2225 3850);
FORCEPROP 2 LAST $XR0 56 
J 0
(-2036 3850);
DISPLAY 0.638298 (-2036 3850);
PAINT MONO (-2036 3850);
FORCEPROP 1 LAST COMMENT_BODY TRUE
J 0
(-2270 3755);
DISPLAY 0.872340 (-2270 3755);
PAINT GREEN (-2270 3755);
DISPLAY INVISIBLE (-2270 3755);
FORCEPROP 2 LAST PATH I21
J 0
(-2050 3925);
DISPLAY 1.021277 (-2050 3925);
PAINT ORANGE (-2050 3925);
DISPLAY INVISIBLE (-2050 3925);
FORCEPROP 2 LAST CDS_LIB mstr_standard
J 0
(-2225 3850);
PAINT ORANGE (-2225 3850);
DISPLAY INVISIBLE (-2225 3850);
FORCEPROP 1 LAST OFFPAGE TRUE
J 0
(-1900 3725);
DISPLAY 0.872340 (-1900 3725);
PAINT GREEN (-1900 3725);
DISPLAY INVISIBLE (-1900 3725);
FORCEADD RES..1
(-3925 3850);
FORCEPROP 1 LAST VALUE 27.4
J 2
(-4000 3800);
DISPLAY 0.617021 (-4000 3800);
PAINT SKYBLUE (-4000 3800);
FORCEPROP 1 LAST WATTAGE 1/16W
J 2
(-3950 3750);
DISPLAY 0.617021 (-3950 3750);
PAINT SKYBLUE (-3950 3750);
FORCEPROP 1 LAST TOLERANCE 1%
J 0
(-3925 3750);
DISPLAY 0.617021 (-3925 3750);
PAINT SKYBLUE (-3925 3750);
FORCEPROP 1 LASTPIN (-4025 3850) $PN 1
J 0
(-4013 3862);
DISPLAY 0.617021 (-4013 3862);
PAINT ORANGE (-4013 3862);
FORCEPROP 1 LASTPIN (-3825 3850) $PN 2
J 0
(-3863 3862);
DISPLAY 0.617021 (-3863 3862);
PAINT ORANGE (-3863 3862);
FORCEPROP 1 LAST MATERIAL CHIP
J 0
(-3875 3800);
DISPLAY 0.617021 (-3875 3800);
PAINT SKYBLUE (-3875 3800);
FORCEPROP 1 LAST PACK_TYPE 0402
J 0
(-3850 3750);
DISPLAY 0.617021 (-3850 3750);
PAINT SKYBLUE (-3850 3750);
FORCEPROP 1 LAST LOCATION R4D21
J 0
(-3975 3900);
DISPLAY 0.617021 (-3975 3900);
PAINT AQUA (-3975 3900);
FORCEPROP 1 LAST PART_NUMBER G21796-182
J 0
(-3800 3850);
DISPLAY 0.617021 (-3800 3850);
PAINT BLUE (-3800 3850);
FORCEPROP 0 LAST ROOM DB1200Z
J 0
(-3975 4000);
DISPLAY 1.021277 (-3975 4000);
PAINT ORANGE (-3975 4000);
DISPLAY INVISIBLE (-3975 4000);
FORCEPROP 1 LAST PATH I24
J 0
(-3975 4000);
DISPLAY 0.978723 (-3975 4000);
PAINT WHITE (-3975 4000);
DISPLAY INVISIBLE (-3975 4000);
FORCEPROP 2 LAST CDS_LOCATION R4D21
J 0
(-3975 3900);
DISPLAY 0.617021 (-3975 3900);
PAINT AQUA (-3975 3900);
DISPLAY INVISIBLE (-3975 3900);
FORCEPROP 2 LAST SEC 1
J 0
(-3975 4050);
DISPLAY 0.680851 (-3975 4050);
PAINT MONO (-3975 4050);
DISPLAY INVISIBLE (-3975 4050);
FORCEPROP 2 LAST SEC_TYPE 0402
J 0
(-3975 4050);
DISPLAY 1.021277 (-3975 4050);
PAINT ORANGE (-3975 4050);
DISPLAY INVISIBLE (-3975 4050);
FORCEPROP 2 LAST CDS_LIB mstr_discrete
J 0
(-3925 3850);
PAINT ORANGE (-3925 3850);
DISPLAY INVISIBLE (-3925 3850);
FORCEPROP 0 LAST BOM_COST SYS_CLOCK
J 0
(-3975 4100);
DISPLAY 1.021277 (-3975 4100);
PAINT ORANGE (-3975 4100);
DISPLAY INVISIBLE (-3975 4100);
FORCEADD OFFPAGE..1
(-4900 3850);
FORCEPROP 2 LAST $XR0 102 
J 0
(-5152 3850);
DISPLAY 0.638298 (-5152 3850);
PAINT MONO (-5152 3850);
FORCEPROP 2 LAST CDS_LIB mstr_standard
J 0
(-4900 3850);
PAINT ORANGE (-4900 3850);
DISPLAY INVISIBLE (-4900 3850);
FORCEPROP 2 LAST PATH I25
J 0
(-4850 3925);
DISPLAY 1.021277 (-4850 3925);
PAINT ORANGE (-4850 3925);
DISPLAY INVISIBLE (-4850 3925);
FORCEPROP 1 LAST COMMENT_BODY TRUE
J 0
(-4775 3750);
DISPLAY 0.872340 (-4775 3750);
PAINT GREEN (-4775 3750);
DISPLAY INVISIBLE (-4775 3750);
FORCEPROP 1 LAST OFFPAGE TRUE
J 0
(-4575 3725);
DISPLAY 0.872340 (-4575 3725);
PAINT GREEN (-4575 3725);
DISPLAY INVISIBLE (-4575 3725);
FORCEADD OFFPAGE..2
(-2225 3525);
FORCEPROP 2 LAST $XR0 63 
J 0
(-2036 3525);
DISPLAY 0.638298 (-2036 3525);
PAINT MONO (-2036 3525);
FORCEPROP 1 LAST COMMENT_BODY TRUE
J 0
(-2270 3430);
DISPLAY 0.872340 (-2270 3430);
PAINT GREEN (-2270 3430);
DISPLAY INVISIBLE (-2270 3430);
FORCEPROP 2 LAST CDS_LIB mstr_standard
J 0
(-2225 3525);
PAINT ORANGE (-2225 3525);
DISPLAY INVISIBLE (-2225 3525);
FORCEPROP 2 LAST PATH I26
J 0
(-2050 3600);
DISPLAY 1.021277 (-2050 3600);
PAINT ORANGE (-2050 3600);
DISPLAY INVISIBLE (-2050 3600);
FORCEPROP 1 LAST OFFPAGE TRUE
J 0
(-1900 3400);
DISPLAY 0.872340 (-1900 3400);
PAINT GREEN (-1900 3400);
DISPLAY INVISIBLE (-1900 3400);
FORCEADD RES..1
(-3925 3525);
FORCEPROP 1 LAST VALUE 27.4
J 2
(-4000 3475);
DISPLAY 0.617021 (-4000 3475);
PAINT SKYBLUE (-4000 3475);
FORCEPROP 1 LASTPIN (-4025 3525) $PN 1
J 0
(-4013 3537);
DISPLAY 0.617021 (-4013 3537);
PAINT ORANGE (-4013 3537);
FORCEPROP 1 LAST WATTAGE 1/16W
J 2
(-3950 3425);
DISPLAY 0.617021 (-3950 3425);
PAINT SKYBLUE (-3950 3425);
FORCEPROP 1 LAST TOLERANCE 1%
J 0
(-3925 3425);
DISPLAY 0.617021 (-3925 3425);
PAINT SKYBLUE (-3925 3425);
FORCEPROP 1 LASTPIN (-3825 3525) $PN 2
J 0
(-3863 3537);
DISPLAY 0.617021 (-3863 3537);
PAINT ORANGE (-3863 3537);
FORCEPROP 1 LAST MATERIAL CHIP
J 0
(-3875 3475);
DISPLAY 0.617021 (-3875 3475);
PAINT SKYBLUE (-3875 3475);
FORCEPROP 1 LAST PACK_TYPE 0402
J 0
(-3850 3425);
DISPLAY 0.617021 (-3850 3425);
PAINT SKYBLUE (-3850 3425);
FORCEPROP 1 LAST LOCATION R4D13
J 0
(-3975 3575);
DISPLAY 0.617021 (-3975 3575);
PAINT AQUA (-3975 3575);
FORCEPROP 1 LAST PART_NUMBER G21796-182
J 0
(-3800 3525);
DISPLAY 0.617021 (-3800 3525);
PAINT BLUE (-3800 3525);
FORCEPROP 2 LAST CDS_LIB mstr_discrete
J 0
(-3925 3525);
PAINT ORANGE (-3925 3525);
DISPLAY INVISIBLE (-3925 3525);
FORCEPROP 2 LAST CDS_LOCATION R4D13
J 0
(-3975 3575);
DISPLAY 0.617021 (-3975 3575);
PAINT AQUA (-3975 3575);
DISPLAY INVISIBLE (-3975 3575);
FORCEPROP 0 LAST ROOM DB1200Z
J 0
(-3975 3675);
DISPLAY 1.021277 (-3975 3675);
PAINT ORANGE (-3975 3675);
DISPLAY INVISIBLE (-3975 3675);
FORCEPROP 1 LAST PATH I29
J 0
(-3975 3675);
DISPLAY 0.978723 (-3975 3675);
PAINT WHITE (-3975 3675);
DISPLAY INVISIBLE (-3975 3675);
FORCEPROP 2 LAST SEC 1
J 0
(-3975 3725);
DISPLAY 0.680851 (-3975 3725);
PAINT MONO (-3975 3725);
DISPLAY INVISIBLE (-3975 3725);
FORCEPROP 2 LAST SEC_TYPE 0402
J 0
(-3975 3725);
DISPLAY 1.021277 (-3975 3725);
PAINT ORANGE (-3975 3725);
DISPLAY INVISIBLE (-3975 3725);
FORCEPROP 0 LAST BOM_COST SYS_CLOCK
J 0
(-3975 3775);
DISPLAY 1.021277 (-3975 3775);
PAINT ORANGE (-3975 3775);
DISPLAY INVISIBLE (-3975 3775);
FORCEADD OFFPAGE..1
(-4900 3525);
FORCEPROP 2 LAST $XR0 102 
J 0
(-5152 3525);
DISPLAY 0.638298 (-5152 3525);
PAINT MONO (-5152 3525);
FORCEPROP 2 LAST CDS_LIB mstr_standard
J 0
(-4900 3525);
PAINT ORANGE (-4900 3525);
DISPLAY INVISIBLE (-4900 3525);
FORCEPROP 1 LAST COMMENT_BODY TRUE
J 0
(-4775 3425);
DISPLAY 0.872340 (-4775 3425);
PAINT GREEN (-4775 3425);
DISPLAY INVISIBLE (-4775 3425);
FORCEPROP 2 LAST PATH I30
J 0
(-4850 3600);
DISPLAY 1.021277 (-4850 3600);
PAINT ORANGE (-4850 3600);
DISPLAY INVISIBLE (-4850 3600);
FORCEPROP 1 LAST OFFPAGE TRUE
J 0
(-4575 3400);
DISPLAY 0.872340 (-4575 3400);
PAINT GREEN (-4575 3400);
DISPLAY INVISIBLE (-4575 3400);
FORCEADD OFFPAGE..2
(-2225 3200);
FORCEPROP 2 LAST $XR0 63 
J 0
(-2036 3200);
DISPLAY 0.638298 (-2036 3200);
PAINT MONO (-2036 3200);
FORCEPROP 1 LAST COMMENT_BODY TRUE
J 0
(-2270 3105);
DISPLAY 0.872340 (-2270 3105);
PAINT GREEN (-2270 3105);
DISPLAY INVISIBLE (-2270 3105);
FORCEPROP 2 LAST CDS_LIB mstr_standard
J 0
(-2225 3200);
PAINT ORANGE (-2225 3200);
DISPLAY INVISIBLE (-2225 3200);
FORCEPROP 2 LAST PATH I31
J 0
(-2050 3275);
DISPLAY 1.021277 (-2050 3275);
PAINT ORANGE (-2050 3275);
DISPLAY INVISIBLE (-2050 3275);
FORCEPROP 1 LAST OFFPAGE TRUE
J 0
(-1900 3075);
DISPLAY 0.872340 (-1900 3075);
PAINT GREEN (-1900 3075);
DISPLAY INVISIBLE (-1900 3075);
FORCEADD RES..1
(-3925 3200);
FORCEPROP 1 LAST VALUE 27.4
J 2
(-4000 3150);
DISPLAY 0.617021 (-4000 3150);
PAINT SKYBLUE (-4000 3150);
FORCEPROP 1 LASTPIN (-4025 3200) $PN 1
J 0
(-4013 3212);
DISPLAY 0.617021 (-4013 3212);
PAINT ORANGE (-4013 3212);
FORCEPROP 1 LAST WATTAGE 1/16W
J 2
(-3950 3100);
DISPLAY 0.617021 (-3950 3100);
PAINT SKYBLUE (-3950 3100);
FORCEPROP 1 LAST TOLERANCE 1%
J 0
(-3925 3100);
DISPLAY 0.617021 (-3925 3100);
PAINT SKYBLUE (-3925 3100);
FORCEPROP 1 LASTPIN (-3825 3200) $PN 2
J 0
(-3863 3212);
DISPLAY 0.617021 (-3863 3212);
PAINT ORANGE (-3863 3212);
FORCEPROP 1 LAST MATERIAL CHIP
J 0
(-3875 3150);
DISPLAY 0.617021 (-3875 3150);
PAINT SKYBLUE (-3875 3150);
FORCEPROP 1 LAST PACK_TYPE 0402
J 0
(-3850 3100);
DISPLAY 0.617021 (-3850 3100);
PAINT SKYBLUE (-3850 3100);
FORCEPROP 1 LAST LOCATION R4D16
J 0
(-3975 3250);
DISPLAY 0.617021 (-3975 3250);
PAINT AQUA (-3975 3250);
FORCEPROP 1 LAST PART_NUMBER G21796-182
J 0
(-3800 3200);
DISPLAY 0.617021 (-3800 3200);
PAINT BLUE (-3800 3200);
FORCEPROP 2 LAST CDS_LOCATION R4D16
J 0
(-3975 3250);
DISPLAY 0.617021 (-3975 3250);
PAINT AQUA (-3975 3250);
DISPLAY INVISIBLE (-3975 3250);
FORCEPROP 2 LAST CDS_LIB mstr_discrete
J 0
(-3925 3200);
PAINT ORANGE (-3925 3200);
DISPLAY INVISIBLE (-3925 3200);
FORCEPROP 2 LAST SEC_TYPE 0402
J 0
(-3975 3400);
DISPLAY 1.021277 (-3975 3400);
PAINT ORANGE (-3975 3400);
DISPLAY INVISIBLE (-3975 3400);
FORCEPROP 0 LAST BOM_COST SYS_CLOCK
J 0
(-3975 3450);
DISPLAY 1.021277 (-3975 3450);
PAINT ORANGE (-3975 3450);
DISPLAY INVISIBLE (-3975 3450);
FORCEPROP 2 LAST SEC 1
J 0
(-3975 3400);
DISPLAY 0.680851 (-3975 3400);
PAINT MONO (-3975 3400);
DISPLAY INVISIBLE (-3975 3400);
FORCEPROP 1 LAST PATH I34
J 0
(-3975 3350);
DISPLAY 0.978723 (-3975 3350);
PAINT WHITE (-3975 3350);
DISPLAY INVISIBLE (-3975 3350);
FORCEPROP 0 LAST ROOM DB1200Z
J 0
(-3975 3350);
DISPLAY 1.021277 (-3975 3350);
PAINT ORANGE (-3975 3350);
DISPLAY INVISIBLE (-3975 3350);
FORCEADD OFFPAGE..1
(-4900 3200);
FORCEPROP 2 LAST $XR0 102 
J 0
(-5152 3200);
DISPLAY 0.638298 (-5152 3200);
PAINT MONO (-5152 3200);
FORCEPROP 2 LAST CDS_LIB mstr_standard
J 0
(-4900 3200);
PAINT ORANGE (-4900 3200);
DISPLAY INVISIBLE (-4900 3200);
FORCEPROP 2 LAST PATH I35
J 0
(-4850 3275);
DISPLAY 1.021277 (-4850 3275);
PAINT ORANGE (-4850 3275);
DISPLAY INVISIBLE (-4850 3275);
FORCEPROP 1 LAST COMMENT_BODY TRUE
J 0
(-4775 3100);
DISPLAY 0.872340 (-4775 3100);
PAINT GREEN (-4775 3100);
DISPLAY INVISIBLE (-4775 3100);
FORCEPROP 1 LAST OFFPAGE TRUE
J 0
(-4575 3075);
DISPLAY 0.872340 (-4575 3075);
PAINT GREEN (-4575 3075);
DISPLAY INVISIBLE (-4575 3075);
FORCEADD OFFPAGE..2
(-2225 2875);
FORCEPROP 2 LAST $XR0 55 
J 0
(-2036 2875);
DISPLAY 0.638298 (-2036 2875);
PAINT MONO (-2036 2875);
FORCEPROP 1 LAST COMMENT_BODY TRUE
J 0
(-2270 2780);
DISPLAY 0.872340 (-2270 2780);
PAINT GREEN (-2270 2780);
DISPLAY INVISIBLE (-2270 2780);
FORCEPROP 2 LAST CDS_LIB mstr_standard
J 0
(-2225 2875);
PAINT ORANGE (-2225 2875);
DISPLAY INVISIBLE (-2225 2875);
FORCEPROP 2 LAST PATH I36
J 0
(-2050 2950);
DISPLAY 1.021277 (-2050 2950);
PAINT ORANGE (-2050 2950);
DISPLAY INVISIBLE (-2050 2950);
FORCEPROP 1 LAST OFFPAGE TRUE
J 0
(-1900 2750);
DISPLAY 0.872340 (-1900 2750);
PAINT GREEN (-1900 2750);
DISPLAY INVISIBLE (-1900 2750);
FORCEADD RES..1
(-3925 2875);
FORCEPROP 1 LAST VALUE 27.4
J 2
(-4000 2825);
DISPLAY 0.617021 (-4000 2825);
PAINT SKYBLUE (-4000 2825);
FORCEPROP 1 LAST WATTAGE 1/16W
J 2
(-3950 2775);
DISPLAY 0.617021 (-3950 2775);
PAINT SKYBLUE (-3950 2775);
FORCEPROP 1 LAST TOLERANCE 1%
J 0
(-3925 2775);
DISPLAY 0.617021 (-3925 2775);
PAINT SKYBLUE (-3925 2775);
FORCEPROP 1 LASTPIN (-4025 2875) $PN 1
J 0
(-4013 2887);
DISPLAY 0.617021 (-4013 2887);
PAINT ORANGE (-4013 2887);
FORCEPROP 1 LAST LOCATION R4D9
J 0
(-3975 2925);
DISPLAY 0.617021 (-3975 2925);
PAINT AQUA (-3975 2925);
FORCEPROP 1 LASTPIN (-3825 2875) $PN 2
J 0
(-3863 2887);
DISPLAY 0.617021 (-3863 2887);
PAINT ORANGE (-3863 2887);
FORCEPROP 1 LAST MATERIAL CHIP
J 0
(-3875 2825);
DISPLAY 0.617021 (-3875 2825);
PAINT SKYBLUE (-3875 2825);
FORCEPROP 1 LAST PACK_TYPE 0402
J 0
(-3850 2775);
DISPLAY 0.617021 (-3850 2775);
PAINT SKYBLUE (-3850 2775);
FORCEPROP 1 LAST PART_NUMBER G21796-182
J 0
(-3800 2875);
DISPLAY 0.617021 (-3800 2875);
PAINT BLUE (-3800 2875);
FORCEPROP 2 LAST CDS_LOCATION R4D9
J 0
(-3975 2925);
DISPLAY 0.617021 (-3975 2925);
PAINT AQUA (-3975 2925);
DISPLAY INVISIBLE (-3975 2925);
FORCEPROP 1 LAST PATH I39
J 0
(-3975 3025);
DISPLAY 0.978723 (-3975 3025);
PAINT WHITE (-3975 3025);
DISPLAY INVISIBLE (-3975 3025);
FORCEPROP 0 LAST ROOM DB1200Z
J 0
(-3975 3025);
DISPLAY 1.021277 (-3975 3025);
PAINT ORANGE (-3975 3025);
DISPLAY INVISIBLE (-3975 3025);
FORCEPROP 2 LAST CDS_LIB mstr_discrete
J 0
(-3925 2875);
PAINT ORANGE (-3925 2875);
DISPLAY INVISIBLE (-3925 2875);
FORCEPROP 2 LAST SEC_TYPE 0402
J 0
(-3975 3075);
DISPLAY 1.021277 (-3975 3075);
PAINT ORANGE (-3975 3075);
DISPLAY INVISIBLE (-3975 3075);
FORCEPROP 0 LAST BOM_COST SYS_CLOCK
J 0
(-3975 3125);
DISPLAY 1.021277 (-3975 3125);
PAINT ORANGE (-3975 3125);
DISPLAY INVISIBLE (-3975 3125);
FORCEPROP 2 LAST SEC 1
J 0
(-3975 3075);
DISPLAY 0.680851 (-3975 3075);
PAINT MONO (-3975 3075);
DISPLAY INVISIBLE (-3975 3075);
FORCEADD OFFPAGE..1
(-675 1250);
FORCEPROP 2 LAST $XR0 102 
J 0
(-927 1250);
DISPLAY 0.638298 (-927 1250);
PAINT MONO (-927 1250);
FORCEPROP 2 LAST PATH I4
J 0
(-625 1325);
DISPLAY 1.021277 (-625 1325);
PAINT ORANGE (-625 1325);
DISPLAY INVISIBLE (-625 1325);
FORCEPROP 1 LAST COMMENT_BODY TRUE
J 0
(-550 1150);
DISPLAY 0.872340 (-550 1150);
PAINT GREEN (-550 1150);
DISPLAY INVISIBLE (-550 1150);
FORCEPROP 2 LAST CDS_LIB mstr_standard
J 0
(-675 1250);
PAINT ORANGE (-675 1250);
DISPLAY INVISIBLE (-675 1250);
FORCEPROP 1 LAST OFFPAGE TRUE
J 0
(-350 1125);
DISPLAY 0.872340 (-350 1125);
PAINT GREEN (-350 1125);
DISPLAY INVISIBLE (-350 1125);
FORCEADD OFFPAGE..1
(-4900 2875);
FORCEPROP 2 LAST $XR0 102 
J 0
(-5152 2875);
DISPLAY 0.638298 (-5152 2875);
PAINT MONO (-5152 2875);
FORCEPROP 2 LAST CDS_LIB mstr_standard
J 0
(-4900 2875);
PAINT ORANGE (-4900 2875);
DISPLAY INVISIBLE (-4900 2875);
FORCEPROP 2 LAST PATH I40
J 0
(-4850 2950);
DISPLAY 1.021277 (-4850 2950);
PAINT ORANGE (-4850 2950);
DISPLAY INVISIBLE (-4850 2950);
FORCEPROP 1 LAST COMMENT_BODY TRUE
J 0
(-4775 2775);
DISPLAY 0.872340 (-4775 2775);
PAINT GREEN (-4775 2775);
DISPLAY INVISIBLE (-4775 2775);
FORCEPROP 1 LAST OFFPAGE TRUE
J 0
(-4575 2750);
DISPLAY 0.872340 (-4575 2750);
PAINT GREEN (-4575 2750);
DISPLAY INVISIBLE (-4575 2750);
FORCEADD OFFPAGE..2
(-2225 2550);
FORCEPROP 2 LAST $XR0 55 
J 0
(-2036 2550);
DISPLAY 0.638298 (-2036 2550);
PAINT MONO (-2036 2550);
FORCEPROP 1 LAST COMMENT_BODY TRUE
J 0
(-2270 2455);
DISPLAY 0.872340 (-2270 2455);
PAINT GREEN (-2270 2455);
DISPLAY INVISIBLE (-2270 2455);
FORCEPROP 2 LAST CDS_LIB mstr_standard
J 0
(-2225 2550);
PAINT ORANGE (-2225 2550);
DISPLAY INVISIBLE (-2225 2550);
FORCEPROP 2 LAST PATH I41
J 0
(-2050 2625);
DISPLAY 1.021277 (-2050 2625);
PAINT ORANGE (-2050 2625);
DISPLAY INVISIBLE (-2050 2625);
FORCEPROP 1 LAST OFFPAGE TRUE
J 0
(-1900 2425);
DISPLAY 0.872340 (-1900 2425);
PAINT GREEN (-1900 2425);
DISPLAY INVISIBLE (-1900 2425);
FORCEADD RES..1
(-3925 2550);
FORCEPROP 1 LAST VALUE 27.4
J 2
(-4000 2500);
DISPLAY 0.617021 (-4000 2500);
PAINT SKYBLUE (-4000 2500);
FORCEPROP 1 LAST WATTAGE 1/16W
J 2
(-3950 2450);
DISPLAY 0.617021 (-3950 2450);
PAINT SKYBLUE (-3950 2450);
FORCEPROP 1 LAST TOLERANCE 1%
J 0
(-3925 2450);
DISPLAY 0.617021 (-3925 2450);
PAINT SKYBLUE (-3925 2450);
FORCEPROP 1 LAST MATERIAL CHIP
J 0
(-3875 2500);
DISPLAY 0.617021 (-3875 2500);
PAINT SKYBLUE (-3875 2500);
FORCEPROP 1 LAST PACK_TYPE 0402
J 0
(-3850 2450);
DISPLAY 0.617021 (-3850 2450);
PAINT SKYBLUE (-3850 2450);
FORCEPROP 1 LASTPIN (-4025 2550) $PN 1
J 0
(-4013 2562);
DISPLAY 0.617021 (-4013 2562);
PAINT ORANGE (-4013 2562);
FORCEPROP 1 LASTPIN (-3825 2550) $PN 2
J 0
(-3863 2562);
DISPLAY 0.617021 (-3863 2562);
PAINT ORANGE (-3863 2562);
FORCEPROP 1 LAST LOCATION R4D11
J 0
(-3975 2600);
DISPLAY 0.617021 (-3975 2600);
PAINT AQUA (-3975 2600);
FORCEPROP 1 LAST PART_NUMBER G21796-182
J 0
(-3800 2550);
DISPLAY 0.617021 (-3800 2550);
PAINT BLUE (-3800 2550);
FORCEPROP 2 LAST CDS_LIB mstr_discrete
J 0
(-3925 2550);
PAINT ORANGE (-3925 2550);
DISPLAY INVISIBLE (-3925 2550);
FORCEPROP 2 LAST SEC 1
J 0
(-3975 2750);
DISPLAY 0.680851 (-3975 2750);
PAINT MONO (-3975 2750);
DISPLAY INVISIBLE (-3975 2750);
FORCEPROP 0 LAST ROOM DB1200Z
J 0
(-3975 2700);
DISPLAY 1.021277 (-3975 2700);
PAINT ORANGE (-3975 2700);
DISPLAY INVISIBLE (-3975 2700);
FORCEPROP 1 LAST PATH I44
J 0
(-3975 2700);
DISPLAY 0.978723 (-3975 2700);
PAINT WHITE (-3975 2700);
DISPLAY INVISIBLE (-3975 2700);
FORCEPROP 2 LAST CDS_LOCATION R4D11
J 0
(-3975 2600);
DISPLAY 0.617021 (-3975 2600);
PAINT AQUA (-3975 2600);
DISPLAY INVISIBLE (-3975 2600);
FORCEPROP 2 LAST SEC_TYPE 0402
J 0
(-3975 2750);
DISPLAY 1.021277 (-3975 2750);
PAINT ORANGE (-3975 2750);
DISPLAY INVISIBLE (-3975 2750);
FORCEPROP 0 LAST BOM_COST SYS_CLOCK
J 0
(-3975 2800);
DISPLAY 1.021277 (-3975 2800);
PAINT ORANGE (-3975 2800);
DISPLAY INVISIBLE (-3975 2800);
FORCEADD OFFPAGE..1
(-4900 2550);
FORCEPROP 2 LAST $XR0 102 
J 0
(-5152 2550);
DISPLAY 0.638298 (-5152 2550);
PAINT MONO (-5152 2550);
FORCEPROP 1 LAST COMMENT_BODY TRUE
J 0
(-4775 2450);
DISPLAY 0.872340 (-4775 2450);
PAINT GREEN (-4775 2450);
DISPLAY INVISIBLE (-4775 2450);
FORCEPROP 2 LAST CDS_LIB mstr_standard
J 0
(-4900 2550);
PAINT ORANGE (-4900 2550);
DISPLAY INVISIBLE (-4900 2550);
FORCEPROP 2 LAST PATH I45
J 0
(-4850 2625);
DISPLAY 1.021277 (-4850 2625);
PAINT ORANGE (-4850 2625);
DISPLAY INVISIBLE (-4850 2625);
FORCEPROP 1 LAST OFFPAGE TRUE
J 0
(-4575 2425);
DISPLAY 0.872340 (-4575 2425);
PAINT GREEN (-4575 2425);
DISPLAY INVISIBLE (-4575 2425);
FORCEADD OFFPAGE..2
(-2225 2225);
FORCEPROP 2 LAST $XR0 55 
J 0
(-2036 2225);
DISPLAY 0.638298 (-2036 2225);
PAINT MONO (-2036 2225);
FORCEPROP 1 LAST COMMENT_BODY TRUE
J 0
(-2270 2130);
DISPLAY 0.872340 (-2270 2130);
PAINT GREEN (-2270 2130);
DISPLAY INVISIBLE (-2270 2130);
FORCEPROP 2 LAST CDS_LIB mstr_standard
J 0
(-2225 2225);
PAINT ORANGE (-2225 2225);
DISPLAY INVISIBLE (-2225 2225);
FORCEPROP 2 LAST PATH I46
J 0
(-2050 2300);
DISPLAY 1.021277 (-2050 2300);
PAINT ORANGE (-2050 2300);
DISPLAY INVISIBLE (-2050 2300);
FORCEPROP 1 LAST OFFPAGE TRUE
J 0
(-1900 2100);
DISPLAY 0.872340 (-1900 2100);
PAINT GREEN (-1900 2100);
DISPLAY INVISIBLE (-1900 2100);
FORCEADD RES..1
(-3925 2225);
FORCEPROP 1 LAST VALUE 27.4
J 2
(-4000 2175);
DISPLAY 0.617021 (-4000 2175);
PAINT SKYBLUE (-4000 2175);
FORCEPROP 1 LASTPIN (-4025 2225) $PN 1
J 0
(-4013 2237);
DISPLAY 0.617021 (-4013 2237);
PAINT ORANGE (-4013 2237);
FORCEPROP 1 LAST WATTAGE 1/16W
J 2
(-3950 2125);
DISPLAY 0.617021 (-3950 2125);
PAINT SKYBLUE (-3950 2125);
FORCEPROP 1 LAST LOCATION R4D2
J 0
(-3975 2275);
DISPLAY 0.617021 (-3975 2275);
PAINT AQUA (-3975 2275);
FORCEPROP 1 LAST TOLERANCE 1%
J 0
(-3925 2125);
DISPLAY 0.617021 (-3925 2125);
PAINT SKYBLUE (-3925 2125);
FORCEPROP 1 LASTPIN (-3825 2225) $PN 2
J 0
(-3863 2237);
DISPLAY 0.617021 (-3863 2237);
PAINT ORANGE (-3863 2237);
FORCEPROP 1 LAST MATERIAL CHIP
J 0
(-3875 2175);
DISPLAY 0.617021 (-3875 2175);
PAINT SKYBLUE (-3875 2175);
FORCEPROP 1 LAST PACK_TYPE 0402
J 0
(-3850 2125);
DISPLAY 0.617021 (-3850 2125);
PAINT SKYBLUE (-3850 2125);
FORCEPROP 1 LAST PART_NUMBER G21796-182
J 0
(-3800 2225);
DISPLAY 0.617021 (-3800 2225);
PAINT BLUE (-3800 2225);
FORCEPROP 2 LAST CDS_LOCATION R4D2
J 0
(-3975 2275);
DISPLAY 0.617021 (-3975 2275);
PAINT AQUA (-3975 2275);
DISPLAY INVISIBLE (-3975 2275);
FORCEPROP 2 LAST CDS_LIB mstr_discrete
J 0
(-3925 2225);
PAINT ORANGE (-3925 2225);
DISPLAY INVISIBLE (-3925 2225);
FORCEPROP 0 LAST ROOM DB1200Z
J 0
(-3975 2375);
DISPLAY 1.021277 (-3975 2375);
PAINT ORANGE (-3975 2375);
DISPLAY INVISIBLE (-3975 2375);
FORCEPROP 1 LAST PATH I49
J 0
(-3975 2375);
DISPLAY 0.978723 (-3975 2375);
PAINT WHITE (-3975 2375);
DISPLAY INVISIBLE (-3975 2375);
FORCEPROP 2 LAST $SEC 1
J 0
(-3975 2425);
PAINT MONO (-3975 2425);
DISPLAY INVISIBLE (-3975 2425);
FORCEPROP 2 LAST CDS_SEC 1
J 0
(-3975 2425);
PAINT MONO (-3975 2425);
DISPLAY INVISIBLE (-3975 2425);
FORCEPROP 0 LAST BOM_COST SYS_CLOCK
J 0
(-3975 2475);
DISPLAY 1.021277 (-3975 2475);
PAINT ORANGE (-3975 2475);
DISPLAY INVISIBLE (-3975 2475);
FORCEADD OFFPAGE..2
(1950 1250);
FORCEPROP 2 LAST $XR0 21 
J 0
(2139 1250);
DISPLAY 0.638298 (2139 1250);
PAINT MONO (2139 1250);
FORCEPROP 1 LAST COMMENT_BODY TRUE
J 0
(1905 1155);
DISPLAY 0.872340 (1905 1155);
PAINT GREEN (1905 1155);
DISPLAY INVISIBLE (1905 1155);
FORCEPROP 2 LAST CDS_LIB mstr_standard
J 0
(1950 1250);
PAINT ORANGE (1950 1250);
DISPLAY INVISIBLE (1950 1250);
FORCEPROP 2 LAST PATH I5
J 0
(2125 1325);
DISPLAY 1.021277 (2125 1325);
PAINT ORANGE (2125 1325);
DISPLAY INVISIBLE (2125 1325);
FORCEPROP 1 LAST OFFPAGE TRUE
J 0
(2275 1125);
DISPLAY 0.872340 (2275 1125);
PAINT GREEN (2275 1125);
DISPLAY INVISIBLE (2275 1125);
FORCEADD OFFPAGE..1
(-4900 2225);
FORCEPROP 2 LAST $XR0 102 
J 0
(-5152 2225);
DISPLAY 0.638298 (-5152 2225);
PAINT MONO (-5152 2225);
FORCEPROP 2 LAST CDS_LIB mstr_standard
J 0
(-4900 2225);
PAINT ORANGE (-4900 2225);
DISPLAY INVISIBLE (-4900 2225);
FORCEPROP 2 LAST PATH I50
J 0
(-4850 2300);
DISPLAY 1.021277 (-4850 2300);
PAINT ORANGE (-4850 2300);
DISPLAY INVISIBLE (-4850 2300);
FORCEPROP 1 LAST COMMENT_BODY TRUE
J 0
(-4775 2125);
DISPLAY 0.872340 (-4775 2125);
PAINT GREEN (-4775 2125);
DISPLAY INVISIBLE (-4775 2125);
FORCEPROP 1 LAST OFFPAGE TRUE
J 0
(-4575 2100);
DISPLAY 0.872340 (-4575 2100);
PAINT GREEN (-4575 2100);
DISPLAY INVISIBLE (-4575 2100);
FORCEADD OFFPAGE..2
(-2225 1900);
FORCEPROP 2 LAST $XR0 55 
J 0
(-2036 1900);
DISPLAY 0.638298 (-2036 1900);
PAINT MONO (-2036 1900);
FORCEPROP 1 LAST COMMENT_BODY TRUE
J 0
(-2270 1805);
DISPLAY 0.872340 (-2270 1805);
PAINT GREEN (-2270 1805);
DISPLAY INVISIBLE (-2270 1805);
FORCEPROP 2 LAST CDS_LIB mstr_standard
J 0
(-2225 1900);
PAINT ORANGE (-2225 1900);
DISPLAY INVISIBLE (-2225 1900);
FORCEPROP 2 LAST PATH I51
J 0
(-2050 1975);
DISPLAY 1.021277 (-2050 1975);
PAINT ORANGE (-2050 1975);
DISPLAY INVISIBLE (-2050 1975);
FORCEPROP 1 LAST OFFPAGE TRUE
J 0
(-1900 1775);
DISPLAY 0.872340 (-1900 1775);
PAINT GREEN (-1900 1775);
DISPLAY INVISIBLE (-1900 1775);
FORCEADD RES..1
(-3925 1900);
FORCEPROP 1 LAST VALUE 27.4
J 2
(-4000 1850);
DISPLAY 0.617021 (-4000 1850);
PAINT SKYBLUE (-4000 1850);
FORCEPROP 1 LASTPIN (-4025 1900) $PN 1
J 0
(-4013 1912);
DISPLAY 0.617021 (-4013 1912);
PAINT ORANGE (-4013 1912);
FORCEPROP 1 LAST LOCATION R4D1
J 0
(-3975 1950);
DISPLAY 0.617021 (-3975 1950);
PAINT AQUA (-3975 1950);
FORCEPROP 1 LAST WATTAGE 1/16W
J 2
(-3950 1800);
DISPLAY 0.617021 (-3950 1800);
PAINT SKYBLUE (-3950 1800);
FORCEPROP 1 LAST TOLERANCE 1%
J 0
(-3925 1800);
DISPLAY 0.617021 (-3925 1800);
PAINT SKYBLUE (-3925 1800);
FORCEPROP 1 LASTPIN (-3825 1900) $PN 2
J 0
(-3863 1912);
DISPLAY 0.617021 (-3863 1912);
PAINT ORANGE (-3863 1912);
FORCEPROP 1 LAST MATERIAL CHIP
J 0
(-3875 1850);
DISPLAY 0.617021 (-3875 1850);
PAINT SKYBLUE (-3875 1850);
FORCEPROP 1 LAST PACK_TYPE 0402
J 0
(-3850 1800);
DISPLAY 0.617021 (-3850 1800);
PAINT SKYBLUE (-3850 1800);
FORCEPROP 1 LAST PART_NUMBER G21796-182
J 0
(-3800 1900);
DISPLAY 0.617021 (-3800 1900);
PAINT BLUE (-3800 1900);
FORCEPROP 2 LAST CDS_LOCATION R4D1
J 0
(-3975 1950);
DISPLAY 0.617021 (-3975 1950);
PAINT AQUA (-3975 1950);
DISPLAY INVISIBLE (-3975 1950);
FORCEPROP 2 LAST CDS_LIB mstr_discrete
J 0
(-3925 1900);
PAINT ORANGE (-3925 1900);
DISPLAY INVISIBLE (-3925 1900);
FORCEPROP 2 LAST SEC_TYPE 0402
J 0
(-3975 2100);
DISPLAY 1.021277 (-3975 2100);
PAINT ORANGE (-3975 2100);
DISPLAY INVISIBLE (-3975 2100);
FORCEPROP 0 LAST BOM_COST SYS_CLOCK
J 0
(-3975 2150);
DISPLAY 1.021277 (-3975 2150);
PAINT ORANGE (-3975 2150);
DISPLAY INVISIBLE (-3975 2150);
FORCEPROP 0 LAST ROOM DB1200Z
J 0
(-3975 2050);
DISPLAY 1.021277 (-3975 2050);
PAINT ORANGE (-3975 2050);
DISPLAY INVISIBLE (-3975 2050);
FORCEPROP 1 LAST PATH I54
J 0
(-3975 2050);
DISPLAY 0.978723 (-3975 2050);
PAINT WHITE (-3975 2050);
DISPLAY INVISIBLE (-3975 2050);
FORCEPROP 2 LAST SEC 1
J 0
(-3975 2100);
DISPLAY 0.680851 (-3975 2100);
PAINT MONO (-3975 2100);
DISPLAY INVISIBLE (-3975 2100);
FORCEADD OFFPAGE..1
(-4900 1900);
FORCEPROP 2 LAST $XR0 102 
J 0
(-5152 1900);
DISPLAY 0.638298 (-5152 1900);
PAINT MONO (-5152 1900);
FORCEPROP 2 LAST CDS_LIB mstr_standard
J 0
(-4900 1900);
PAINT ORANGE (-4900 1900);
DISPLAY INVISIBLE (-4900 1900);
FORCEPROP 2 LAST PATH I55
J 0
(-4850 1975);
DISPLAY 1.021277 (-4850 1975);
PAINT ORANGE (-4850 1975);
DISPLAY INVISIBLE (-4850 1975);
FORCEPROP 1 LAST COMMENT_BODY TRUE
J 0
(-4775 1800);
DISPLAY 0.872340 (-4775 1800);
PAINT GREEN (-4775 1800);
DISPLAY INVISIBLE (-4775 1800);
FORCEPROP 1 LAST OFFPAGE TRUE
J 0
(-4575 1775);
DISPLAY 0.872340 (-4575 1775);
PAINT GREEN (-4575 1775);
DISPLAY INVISIBLE (-4575 1775);
FORCEADD OFFPAGE..2
(-2225 1575);
FORCEPROP 2 LAST $XR0 55 
J 0
(-2036 1575);
DISPLAY 0.638298 (-2036 1575);
PAINT MONO (-2036 1575);
FORCEPROP 1 LAST COMMENT_BODY TRUE
J 0
(-2270 1480);
DISPLAY 0.872340 (-2270 1480);
PAINT GREEN (-2270 1480);
DISPLAY INVISIBLE (-2270 1480);
FORCEPROP 2 LAST CDS_LIB mstr_standard
J 0
(-2225 1575);
PAINT ORANGE (-2225 1575);
DISPLAY INVISIBLE (-2225 1575);
FORCEPROP 2 LAST PATH I56
J 0
(-2050 1650);
DISPLAY 1.021277 (-2050 1650);
PAINT ORANGE (-2050 1650);
DISPLAY INVISIBLE (-2050 1650);
FORCEPROP 1 LAST OFFPAGE TRUE
J 0
(-1900 1450);
DISPLAY 0.872340 (-1900 1450);
PAINT GREEN (-1900 1450);
DISPLAY INVISIBLE (-1900 1450);
FORCEADD RES..1
(-3925 1575);
FORCEPROP 1 LAST VALUE 27.4
J 2
(-4000 1525);
DISPLAY 0.617021 (-4000 1525);
PAINT SKYBLUE (-4000 1525);
FORCEPROP 1 LAST WATTAGE 1/16W
J 2
(-3950 1475);
DISPLAY 0.617021 (-3950 1475);
PAINT SKYBLUE (-3950 1475);
FORCEPROP 1 LAST TOLERANCE 1%
J 0
(-3925 1475);
DISPLAY 0.617021 (-3925 1475);
PAINT SKYBLUE (-3925 1475);
FORCEPROP 1 LAST PACK_TYPE 0402
J 0
(-3850 1475);
DISPLAY 0.617021 (-3850 1475);
PAINT SKYBLUE (-3850 1475);
FORCEPROP 1 LAST MATERIAL CHIP
J 0
(-3875 1525);
DISPLAY 0.617021 (-3875 1525);
PAINT SKYBLUE (-3875 1525);
FORCEPROP 1 LASTPIN (-4025 1575) $PN 1
J 0
(-4013 1587);
DISPLAY 0.617021 (-4013 1587);
PAINT ORANGE (-4013 1587);
FORCEPROP 1 LAST LOCATION R4D4
J 0
(-3975 1625);
DISPLAY 0.617021 (-3975 1625);
PAINT AQUA (-3975 1625);
FORCEPROP 1 LASTPIN (-3825 1575) $PN 2
J 0
(-3863 1587);
DISPLAY 0.617021 (-3863 1587);
PAINT ORANGE (-3863 1587);
FORCEPROP 1 LAST PART_NUMBER G21796-182
J 0
(-3800 1575);
DISPLAY 0.617021 (-3800 1575);
PAINT BLUE (-3800 1575);
FORCEPROP 2 LAST CDS_LOCATION R4D4
J 0
(-3975 1625);
DISPLAY 0.617021 (-3975 1625);
PAINT AQUA (-3975 1625);
DISPLAY INVISIBLE (-3975 1625);
FORCEPROP 1 LAST PATH I59
J 0
(-3975 1725);
DISPLAY 0.978723 (-3975 1725);
PAINT WHITE (-3975 1725);
DISPLAY INVISIBLE (-3975 1725);
FORCEPROP 0 LAST ROOM DB1200Z
J 0
(-3975 1725);
DISPLAY 1.021277 (-3975 1725);
PAINT ORANGE (-3975 1725);
DISPLAY INVISIBLE (-3975 1725);
FORCEPROP 2 LAST CDS_LIB mstr_discrete
J 0
(-3925 1575);
PAINT ORANGE (-3925 1575);
DISPLAY INVISIBLE (-3925 1575);
FORCEPROP 2 LAST SEC 1
J 0
(-3975 1775);
DISPLAY 0.680851 (-3975 1775);
PAINT MONO (-3975 1775);
DISPLAY INVISIBLE (-3975 1775);
FORCEPROP 2 LAST SEC_TYPE 0402
J 0
(-3975 1775);
DISPLAY 1.021277 (-3975 1775);
PAINT ORANGE (-3975 1775);
DISPLAY INVISIBLE (-3975 1775);
FORCEPROP 0 LAST BOM_COST SYS_CLOCK
J 0
(-3975 1825);
DISPLAY 1.021277 (-3975 1825);
PAINT ORANGE (-3975 1825);
DISPLAY INVISIBLE (-3975 1825);
FORCEADD OFFPAGE..2
(-2225 4900);
FORCEPROP 2 LAST $XR0 70 
J 0
(-2036 4900);
DISPLAY 0.638298 (-2036 4900);
PAINT MONO (-2036 4900);
FORCEPROP 1 LAST COMMENT_BODY TRUE
J 0
(-2270 4805);
DISPLAY 0.872340 (-2270 4805);
PAINT GREEN (-2270 4805);
DISPLAY INVISIBLE (-2270 4805);
FORCEPROP 2 LAST CDS_LIB mstr_standard
J 0
(-2225 4900);
PAINT ORANGE (-2225 4900);
DISPLAY INVISIBLE (-2225 4900);
FORCEPROP 2 LAST PATH I6
J 0
(-2050 4975);
DISPLAY 1.021277 (-2050 4975);
PAINT ORANGE (-2050 4975);
DISPLAY INVISIBLE (-2050 4975);
FORCEPROP 1 LAST OFFPAGE TRUE
J 0
(-1900 4775);
DISPLAY 0.872340 (-1900 4775);
PAINT GREEN (-1900 4775);
DISPLAY INVISIBLE (-1900 4775);
FORCEADD OFFPAGE..1
(-4900 1575);
FORCEPROP 2 LAST $XR0 102 
J 0
(-5152 1575);
DISPLAY 0.638298 (-5152 1575);
PAINT MONO (-5152 1575);
FORCEPROP 1 LAST COMMENT_BODY TRUE
J 0
(-4775 1475);
DISPLAY 0.872340 (-4775 1475);
PAINT GREEN (-4775 1475);
DISPLAY INVISIBLE (-4775 1475);
FORCEPROP 2 LAST CDS_LIB mstr_standard
J 0
(-4900 1575);
PAINT ORANGE (-4900 1575);
DISPLAY INVISIBLE (-4900 1575);
FORCEPROP 2 LAST PATH I60
J 0
(-4850 1650);
DISPLAY 1.021277 (-4850 1650);
PAINT ORANGE (-4850 1650);
DISPLAY INVISIBLE (-4850 1650);
FORCEPROP 1 LAST OFFPAGE TRUE
J 0
(-4575 1450);
DISPLAY 0.872340 (-4575 1450);
PAINT GREEN (-4575 1450);
DISPLAY INVISIBLE (-4575 1450);
FORCEADD OFFPAGE..2
(-2225 1250);
FORCEPROP 2 LAST $XR0 55 
J 0
(-2036 1250);
DISPLAY 0.638298 (-2036 1250);
PAINT MONO (-2036 1250);
FORCEPROP 1 LAST COMMENT_BODY TRUE
J 0
(-2270 1155);
DISPLAY 0.872340 (-2270 1155);
PAINT GREEN (-2270 1155);
DISPLAY INVISIBLE (-2270 1155);
FORCEPROP 2 LAST CDS_LIB mstr_standard
J 0
(-2225 1250);
PAINT ORANGE (-2225 1250);
DISPLAY INVISIBLE (-2225 1250);
FORCEPROP 2 LAST PATH I61
J 0
(-2050 1325);
DISPLAY 1.021277 (-2050 1325);
PAINT ORANGE (-2050 1325);
DISPLAY INVISIBLE (-2050 1325);
FORCEPROP 1 LAST OFFPAGE TRUE
J 0
(-1900 1125);
DISPLAY 0.872340 (-1900 1125);
PAINT GREEN (-1900 1125);
DISPLAY INVISIBLE (-1900 1125);
FORCEADD RES..1
(-3925 1250);
FORCEPROP 1 LAST VALUE 27.4
J 2
(-4000 1200);
DISPLAY 0.617021 (-4000 1200);
PAINT SKYBLUE (-4000 1200);
FORCEPROP 1 LAST WATTAGE 1/16W
J 2
(-3950 1150);
DISPLAY 0.617021 (-3950 1150);
PAINT SKYBLUE (-3950 1150);
FORCEPROP 1 LAST TOLERANCE 1%
J 0
(-3925 1150);
DISPLAY 0.617021 (-3925 1150);
PAINT SKYBLUE (-3925 1150);
FORCEPROP 1 LASTPIN (-4025 1250) $PN 1
J 0
(-4013 1262);
DISPLAY 0.617021 (-4013 1262);
PAINT ORANGE (-4013 1262);
FORCEPROP 1 LAST LOCATION R4D3
J 0
(-3975 1300);
DISPLAY 0.617021 (-3975 1300);
PAINT AQUA (-3975 1300);
FORCEPROP 1 LASTPIN (-3825 1250) $PN 2
J 0
(-3863 1262);
DISPLAY 0.617021 (-3863 1262);
PAINT ORANGE (-3863 1262);
FORCEPROP 1 LAST PACK_TYPE 0402
J 0
(-3850 1150);
DISPLAY 0.617021 (-3850 1150);
PAINT SKYBLUE (-3850 1150);
FORCEPROP 1 LAST MATERIAL CHIP
J 0
(-3875 1200);
DISPLAY 0.617021 (-3875 1200);
PAINT SKYBLUE (-3875 1200);
FORCEPROP 1 LAST PART_NUMBER G21796-182
J 0
(-3800 1250);
DISPLAY 0.617021 (-3800 1250);
PAINT BLUE (-3800 1250);
FORCEPROP 2 LAST CDS_LIB mstr_discrete
J 0
(-3925 1250);
PAINT ORANGE (-3925 1250);
DISPLAY INVISIBLE (-3925 1250);
FORCEPROP 0 LAST ROOM DB1200Z
J 0
(-3975 1400);
DISPLAY 1.021277 (-3975 1400);
PAINT ORANGE (-3975 1400);
DISPLAY INVISIBLE (-3975 1400);
FORCEPROP 1 LAST PATH I64
J 0
(-3975 1400);
DISPLAY 0.978723 (-3975 1400);
PAINT WHITE (-3975 1400);
DISPLAY INVISIBLE (-3975 1400);
FORCEPROP 2 LAST CDS_LOCATION R4D3
J 0
(-3975 1300);
DISPLAY 0.617021 (-3975 1300);
PAINT AQUA (-3975 1300);
DISPLAY INVISIBLE (-3975 1300);
FORCEPROP 2 LAST SEC 1
J 0
(-3975 1450);
DISPLAY 0.680851 (-3975 1450);
PAINT MONO (-3975 1450);
DISPLAY INVISIBLE (-3975 1450);
FORCEPROP 2 LAST SEC_TYPE 0402
J 0
(-3975 1450);
DISPLAY 1.021277 (-3975 1450);
PAINT ORANGE (-3975 1450);
DISPLAY INVISIBLE (-3975 1450);
FORCEPROP 0 LAST BOM_COST SYS_CLOCK
J 0
(-3975 1500);
DISPLAY 1.021277 (-3975 1500);
PAINT ORANGE (-3975 1500);
DISPLAY INVISIBLE (-3975 1500);
FORCEADD OFFPAGE..1
(-4900 1250);
FORCEPROP 2 LAST $XR0 102 
J 0
(-5152 1250);
DISPLAY 0.638298 (-5152 1250);
PAINT MONO (-5152 1250);
FORCEPROP 2 LAST CDS_LIB mstr_standard
J 0
(-4900 1250);
PAINT ORANGE (-4900 1250);
DISPLAY INVISIBLE (-4900 1250);
FORCEPROP 2 LAST PATH I65
J 0
(-4850 1325);
DISPLAY 1.021277 (-4850 1325);
PAINT ORANGE (-4850 1325);
DISPLAY INVISIBLE (-4850 1325);
FORCEPROP 1 LAST COMMENT_BODY TRUE
J 0
(-4775 1150);
DISPLAY 0.872340 (-4775 1150);
PAINT GREEN (-4775 1150);
DISPLAY INVISIBLE (-4775 1150);
FORCEPROP 1 LAST OFFPAGE TRUE
J 0
(-4575 1125);
DISPLAY 0.872340 (-4575 1125);
PAINT GREEN (-4575 1125);
DISPLAY INVISIBLE (-4575 1125);
FORCEADD OFFPAGE..2
(1950 1575);
FORCEPROP 2 LAST $XR0 21 
J 0
(2139 1575);
DISPLAY 0.638298 (2139 1575);
PAINT MONO (2139 1575);
FORCEPROP 1 LAST COMMENT_BODY TRUE
J 0
(1905 1480);
DISPLAY 0.872340 (1905 1480);
PAINT GREEN (1905 1480);
DISPLAY INVISIBLE (1905 1480);
FORCEPROP 2 LAST CDS_LIB mstr_standard
J 0
(1950 1575);
PAINT ORANGE (1950 1575);
DISPLAY INVISIBLE (1950 1575);
FORCEPROP 1 LAST OFFPAGE TRUE
J 0
(2275 1450);
DISPLAY 0.872340 (2275 1450);
PAINT GREEN (2275 1450);
DISPLAY INVISIBLE (2275 1450);
FORCEPROP 2 LAST PATH I66
J 0
(2125 1650);
DISPLAY 1.021277 (2125 1650);
PAINT ORANGE (2125 1650);
DISPLAY INVISIBLE (2125 1650);
FORCEADD RES..1
(300 1575);
FORCEPROP 1 LAST WATTAGE 1/16W
J 2
(275 1475);
DISPLAY 0.617021 (275 1475);
PAINT SKYBLUE (275 1475);
FORCEPROP 1 LAST PACK_TYPE 0402
J 0
(375 1475);
DISPLAY 0.617021 (375 1475);
PAINT SKYBLUE (375 1475);
FORCEPROP 1 LAST TOLERANCE 1%
J 0
(300 1475);
DISPLAY 0.617021 (300 1475);
PAINT SKYBLUE (300 1475);
FORCEPROP 1 LAST MATERIAL CHIP
J 0
(350 1525);
DISPLAY 0.617021 (350 1525);
PAINT SKYBLUE (350 1525);
FORCEPROP 1 LAST VALUE 27.4
J 2
(225 1525);
DISPLAY 0.617021 (225 1525);
PAINT SKYBLUE (225 1525);
FORCEPROP 1 LASTPIN (200 1575) $PN 1
J 0
(212 1587);
DISPLAY 0.617021 (212 1587);
PAINT ORANGE (212 1587);
FORCEPROP 1 LAST LOCATION R4D29
J 0
(250 1625);
DISPLAY 0.617021 (250 1625);
PAINT AQUA (250 1625);
FORCEPROP 1 LASTPIN (400 1575) $PN 2
J 0
(362 1587);
DISPLAY 0.617021 (362 1587);
PAINT ORANGE (362 1587);
FORCEPROP 1 LAST PART_NUMBER G21796-182
J 0
(425 1575);
DISPLAY 0.617021 (425 1575);
PAINT BLUE (425 1575);
FORCEPROP 0 LAST ROOM DB1200Z
J 0
(250 1725);
DISPLAY 1.021277 (250 1725);
PAINT ORANGE (250 1725);
DISPLAY INVISIBLE (250 1725);
FORCEPROP 1 LAST PATH I69
J 0
(250 1725);
DISPLAY 0.978723 (250 1725);
PAINT WHITE (250 1725);
DISPLAY INVISIBLE (250 1725);
FORCEPROP 2 LAST CDS_LOCATION R4D29
J 0
(250 1625);
DISPLAY 0.617021 (250 1625);
PAINT AQUA (250 1625);
DISPLAY INVISIBLE (250 1625);
FORCEPROP 2 LAST SEC 1
J 0
(250 1775);
DISPLAY 0.680851 (250 1775);
PAINT MONO (250 1775);
DISPLAY INVISIBLE (250 1775);
FORCEPROP 0 LAST BOM_COST SYS_CLOCK
J 0
(250 1825);
DISPLAY 1.021277 (250 1825);
PAINT ORANGE (250 1825);
DISPLAY INVISIBLE (250 1825);
FORCEPROP 2 LAST SEC_TYPE 0402
J 0
(250 1775);
DISPLAY 1.021277 (250 1775);
PAINT ORANGE (250 1775);
DISPLAY INVISIBLE (250 1775);
FORCEPROP 2 LAST CDS_LIB mstr_discrete
J 0
(300 1575);
PAINT ORANGE (300 1575);
DISPLAY INVISIBLE (300 1575);
FORCEADD OFFPAGE..1
(-675 1575);
FORCEPROP 2 LAST $XR0 102 
J 0
(-927 1575);
DISPLAY 0.638298 (-927 1575);
PAINT MONO (-927 1575);
FORCEPROP 1 LAST COMMENT_BODY TRUE
J 0
(-550 1475);
DISPLAY 0.872340 (-550 1475);
PAINT GREEN (-550 1475);
DISPLAY INVISIBLE (-550 1475);
FORCEPROP 2 LAST PATH I70
J 0
(-625 1650);
DISPLAY 1.021277 (-625 1650);
PAINT ORANGE (-625 1650);
DISPLAY INVISIBLE (-625 1650);
FORCEPROP 2 LAST CDS_LIB mstr_standard
J 0
(-675 1575);
PAINT ORANGE (-675 1575);
DISPLAY INVISIBLE (-675 1575);
FORCEPROP 1 LAST OFFPAGE TRUE
J 0
(-350 1450);
DISPLAY 0.872340 (-350 1450);
PAINT GREEN (-350 1450);
DISPLAY INVISIBLE (-350 1450);
FORCEADD OFFPAGE..2
(1950 4825);
FORCEPROP 2 LAST $XR0 36 
J 0
(2139 4825);
DISPLAY 0.638298 (2139 4825);
PAINT MONO (2139 4825);
FORCEPROP 2 LAST CDS_LIB mstr_standard
J 0
(1950 4825);
PAINT ORANGE (1950 4825);
DISPLAY INVISIBLE (1950 4825);
FORCEPROP 1 LAST COMMENT_BODY TRUE
J 0
(1905 4730);
DISPLAY 0.872340 (1905 4730);
PAINT GREEN (1905 4730);
DISPLAY INVISIBLE (1905 4730);
FORCEPROP 2 LAST PATH I71
J 0
(2125 4900);
DISPLAY 1.021277 (2125 4900);
PAINT ORANGE (2125 4900);
DISPLAY INVISIBLE (2125 4900);
FORCEPROP 1 LAST OFFPAGE TRUE
J 0
(2275 4700);
DISPLAY 0.872340 (2275 4700);
PAINT GREEN (2275 4700);
DISPLAY INVISIBLE (2275 4700);
FORCEADD RES..1
(300 4825);
FORCEPROP 1 LASTPIN (200 4825) $PN 1
J 0
(212 4837);
DISPLAY 0.617021 (212 4837);
PAINT ORANGE (212 4837);
FORCEPROP 1 LAST VALUE 27.4
J 2
(225 4775);
DISPLAY 0.617021 (225 4775);
PAINT SKYBLUE (225 4775);
FORCEPROP 1 LAST WATTAGE 1/16W
J 2
(275 4725);
DISPLAY 0.617021 (275 4725);
PAINT SKYBLUE (275 4725);
FORCEPROP 1 LAST LOCATION R4D6
J 0
(250 4875);
DISPLAY 0.617021 (250 4875);
PAINT AQUA (250 4875);
FORCEPROP 1 LASTPIN (400 4825) $PN 2
J 0
(362 4837);
DISPLAY 0.617021 (362 4837);
PAINT ORANGE (362 4837);
FORCEPROP 1 LAST MATERIAL CHIP
J 0
(350 4775);
DISPLAY 0.617021 (350 4775);
PAINT SKYBLUE (350 4775);
FORCEPROP 1 LAST PACK_TYPE 0402
J 0
(375 4725);
DISPLAY 0.617021 (375 4725);
PAINT SKYBLUE (375 4725);
FORCEPROP 1 LAST TOLERANCE 1%
J 0
(300 4725);
DISPLAY 0.617021 (300 4725);
PAINT SKYBLUE (300 4725);
FORCEPROP 1 LAST PART_NUMBER G21796-182
J 0
(425 4825);
DISPLAY 0.617021 (425 4825);
PAINT BLUE (425 4825);
FORCEPROP 0 LAST ROOM DB1200Z
J 0
(250 4975);
DISPLAY 1.021277 (250 4975);
PAINT ORANGE (250 4975);
DISPLAY INVISIBLE (250 4975);
FORCEPROP 1 LAST PATH I74
J 0
(250 4975);
DISPLAY 0.978723 (250 4975);
PAINT WHITE (250 4975);
DISPLAY INVISIBLE (250 4975);
FORCEPROP 2 LAST CDS_LOCATION R4D6
J 0
(250 4875);
DISPLAY 0.617021 (250 4875);
PAINT AQUA (250 4875);
DISPLAY INVISIBLE (250 4875);
FORCEPROP 2 LAST SEC 1
J 0
(250 5025);
DISPLAY 0.680851 (250 5025);
PAINT MONO (250 5025);
DISPLAY INVISIBLE (250 5025);
FORCEPROP 0 LAST BOM_COST SYS_CLOCK
J 0
(250 5075);
DISPLAY 1.021277 (250 5075);
PAINT ORANGE (250 5075);
DISPLAY INVISIBLE (250 5075);
FORCEPROP 2 LAST SEC_TYPE 0402
J 0
(250 5025);
DISPLAY 1.021277 (250 5025);
PAINT ORANGE (250 5025);
DISPLAY INVISIBLE (250 5025);
FORCEPROP 2 LAST CDS_LIB mstr_discrete
J 0
(300 4825);
PAINT ORANGE (300 4825);
DISPLAY INVISIBLE (300 4825);
FORCEADD OFFPAGE..1
(-675 4825);
FORCEPROP 2 LAST $XR0 102 
J 0
(-927 4825);
DISPLAY 0.638298 (-927 4825);
PAINT MONO (-927 4825);
FORCEPROP 2 LAST PATH I75
J 0
(-625 4900);
DISPLAY 1.021277 (-625 4900);
PAINT ORANGE (-625 4900);
DISPLAY INVISIBLE (-625 4900);
FORCEPROP 1 LAST COMMENT_BODY TRUE
J 0
(-550 4725);
DISPLAY 0.872340 (-550 4725);
PAINT GREEN (-550 4725);
DISPLAY INVISIBLE (-550 4725);
FORCEPROP 2 LAST CDS_LIB mstr_standard
J 0
(-675 4825);
PAINT ORANGE (-675 4825);
DISPLAY INVISIBLE (-675 4825);
FORCEPROP 1 LAST OFFPAGE TRUE
J 0
(-350 4700);
DISPLAY 0.872340 (-350 4700);
PAINT GREEN (-350 4700);
DISPLAY INVISIBLE (-350 4700);
FORCEADD OFFPAGE..2
(1950 4500);
FORCEPROP 2 LAST $XR0 36 
J 0
(2139 4500);
DISPLAY 0.638298 (2139 4500);
PAINT MONO (2139 4500);
FORCEPROP 2 LAST CDS_LIB mstr_standard
J 0
(1950 4500);
PAINT ORANGE (1950 4500);
DISPLAY INVISIBLE (1950 4500);
FORCEPROP 1 LAST COMMENT_BODY TRUE
J 0
(1905 4405);
DISPLAY 0.872340 (1905 4405);
PAINT GREEN (1905 4405);
DISPLAY INVISIBLE (1905 4405);
FORCEPROP 1 LAST OFFPAGE TRUE
J 0
(2275 4375);
DISPLAY 0.872340 (2275 4375);
PAINT GREEN (2275 4375);
DISPLAY INVISIBLE (2275 4375);
FORCEPROP 2 LAST PATH I77
J 0
(2125 4575);
DISPLAY 1.021277 (2125 4575);
PAINT ORANGE (2125 4575);
DISPLAY INVISIBLE (2125 4575);
FORCEADD RES..1
(300 4500);
FORCEPROP 1 LASTPIN (200 4500) $PN 1
J 0
(212 4512);
DISPLAY 0.617021 (212 4512);
PAINT ORANGE (212 4512);
FORCEPROP 1 LAST VALUE 27.4
J 2
(225 4450);
DISPLAY 0.617021 (225 4450);
PAINT SKYBLUE (225 4450);
FORCEPROP 1 LAST WATTAGE 1/16W
J 2
(275 4400);
DISPLAY 0.617021 (275 4400);
PAINT SKYBLUE (275 4400);
FORCEPROP 1 LAST LOCATION R4D5
J 0
(250 4550);
DISPLAY 0.617021 (250 4550);
PAINT AQUA (250 4550);
FORCEPROP 1 LASTPIN (400 4500) $PN 2
J 0
(362 4512);
DISPLAY 0.617021 (362 4512);
PAINT ORANGE (362 4512);
FORCEPROP 1 LAST MATERIAL CHIP
J 0
(350 4450);
DISPLAY 0.617021 (350 4450);
PAINT SKYBLUE (350 4450);
FORCEPROP 1 LAST PACK_TYPE 0402
J 0
(375 4400);
DISPLAY 0.617021 (375 4400);
PAINT SKYBLUE (375 4400);
FORCEPROP 1 LAST TOLERANCE 1%
J 0
(300 4400);
DISPLAY 0.617021 (300 4400);
PAINT SKYBLUE (300 4400);
FORCEPROP 1 LAST PART_NUMBER G21796-182
J 0
(425 4500);
DISPLAY 0.617021 (425 4500);
PAINT BLUE (425 4500);
FORCEPROP 2 LAST CDS_LOCATION R4D5
J 0
(250 4550);
DISPLAY 0.617021 (250 4550);
PAINT AQUA (250 4550);
DISPLAY INVISIBLE (250 4550);
FORCEPROP 2 LAST CDS_LIB mstr_discrete
J 0
(300 4500);
PAINT ORANGE (300 4500);
DISPLAY INVISIBLE (300 4500);
FORCEPROP 2 LAST SEC_TYPE 0402
J 0
(250 4700);
DISPLAY 1.021277 (250 4700);
PAINT ORANGE (250 4700);
DISPLAY INVISIBLE (250 4700);
FORCEPROP 0 LAST BOM_COST SYS_CLOCK
J 0
(250 4750);
DISPLAY 1.021277 (250 4750);
PAINT ORANGE (250 4750);
DISPLAY INVISIBLE (250 4750);
FORCEPROP 2 LAST SEC 1
J 0
(250 4700);
DISPLAY 0.680851 (250 4700);
PAINT MONO (250 4700);
DISPLAY INVISIBLE (250 4700);
FORCEPROP 1 LAST PATH I79
J 0
(250 4650);
DISPLAY 0.978723 (250 4650);
PAINT WHITE (250 4650);
DISPLAY INVISIBLE (250 4650);
FORCEPROP 0 LAST ROOM DB1200Z
J 0
(250 4650);
DISPLAY 1.021277 (250 4650);
PAINT ORANGE (250 4650);
DISPLAY INVISIBLE (250 4650);
FORCEADD OFFPAGE..1
(-675 4500);
FORCEPROP 2 LAST $XR0 102 
J 0
(-927 4500);
DISPLAY 0.638298 (-927 4500);
PAINT MONO (-927 4500);
FORCEPROP 1 LAST COMMENT_BODY TRUE
J 0
(-550 4400);
DISPLAY 0.872340 (-550 4400);
PAINT GREEN (-550 4400);
DISPLAY INVISIBLE (-550 4400);
FORCEPROP 2 LAST CDS_LIB mstr_standard
J 0
(-675 4500);
PAINT ORANGE (-675 4500);
DISPLAY INVISIBLE (-675 4500);
FORCEPROP 2 LAST PATH I80
J 0
(-625 4575);
DISPLAY 1.021277 (-625 4575);
PAINT ORANGE (-625 4575);
DISPLAY INVISIBLE (-625 4575);
FORCEPROP 1 LAST OFFPAGE TRUE
J 0
(-350 4375);
DISPLAY 0.872340 (-350 4375);
PAINT GREEN (-350 4375);
DISPLAY INVISIBLE (-350 4375);
FORCEADD OFFPAGE..2
(1950 4175);
FORCEPROP 2 LAST $XR0 22 
J 0
(2139 4175);
DISPLAY 0.638298 (2139 4175);
PAINT MONO (2139 4175);
FORCEPROP 1 LAST OFFPAGE TRUE
J 0
(2275 4050);
DISPLAY 0.872340 (2275 4050);
PAINT GREEN (2275 4050);
DISPLAY INVISIBLE (2275 4050);
FORCEPROP 1 LAST COMMENT_BODY TRUE
J 0
(1905 4080);
DISPLAY 0.872340 (1905 4080);
PAINT GREEN (1905 4080);
DISPLAY INVISIBLE (1905 4080);
FORCEPROP 2 LAST CDS_LIB mstr_standard
J 0
(1950 4175);
PAINT ORANGE (1950 4175);
DISPLAY INVISIBLE (1950 4175);
FORCEPROP 2 LAST PATH I82
J 0
(2125 4250);
DISPLAY 1.021277 (2125 4250);
PAINT ORANGE (2125 4250);
DISPLAY INVISIBLE (2125 4250);
FORCEADD RES..1
(300 4175);
FORCEPROP 1 LAST WATTAGE 1/16W
J 2
(275 4075);
DISPLAY 0.617021 (275 4075);
PAINT SKYBLUE (275 4075);
FORCEPROP 1 LAST PACK_TYPE 0402
J 0
(375 4075);
DISPLAY 0.617021 (375 4075);
PAINT SKYBLUE (375 4075);
FORCEPROP 1 LAST TOLERANCE 1%
J 0
(300 4075);
DISPLAY 0.617021 (300 4075);
PAINT SKYBLUE (300 4075);
FORCEPROP 1 LASTPIN (200 4175) $PN 1
J 0
(212 4187);
DISPLAY 0.617021 (212 4187);
PAINT ORANGE (212 4187);
FORCEPROP 1 LAST VALUE 27.4
J 2
(225 4125);
DISPLAY 0.617021 (225 4125);
PAINT SKYBLUE (225 4125);
FORCEPROP 1 LAST LOCATION R4D8
J 0
(250 4225);
DISPLAY 0.617021 (250 4225);
PAINT AQUA (250 4225);
FORCEPROP 1 LASTPIN (400 4175) $PN 2
J 0
(362 4187);
DISPLAY 0.617021 (362 4187);
PAINT ORANGE (362 4187);
FORCEPROP 1 LAST MATERIAL CHIP
J 0
(350 4125);
DISPLAY 0.617021 (350 4125);
PAINT SKYBLUE (350 4125);
FORCEPROP 1 LAST PART_NUMBER G21796-182
J 0
(425 4175);
DISPLAY 0.617021 (425 4175);
PAINT BLUE (425 4175);
FORCEPROP 0 LAST ROOM DB1200Z
J 0
(250 4325);
DISPLAY 1.021277 (250 4325);
PAINT ORANGE (250 4325);
DISPLAY INVISIBLE (250 4325);
FORCEPROP 1 LAST PATH I84
J 0
(250 4325);
DISPLAY 0.978723 (250 4325);
PAINT WHITE (250 4325);
DISPLAY INVISIBLE (250 4325);
FORCEPROP 2 LAST CDS_LOCATION R4D8
J 0
(250 4225);
DISPLAY 0.617021 (250 4225);
PAINT AQUA (250 4225);
DISPLAY INVISIBLE (250 4225);
FORCEPROP 2 LAST SEC 1
J 0
(250 4375);
DISPLAY 0.680851 (250 4375);
PAINT MONO (250 4375);
DISPLAY INVISIBLE (250 4375);
FORCEPROP 0 LAST BOM_COST SYS_CLOCK
J 0
(250 4425);
DISPLAY 1.021277 (250 4425);
PAINT ORANGE (250 4425);
DISPLAY INVISIBLE (250 4425);
FORCEPROP 2 LAST SEC_TYPE 0402
J 0
(250 4375);
DISPLAY 1.021277 (250 4375);
PAINT ORANGE (250 4375);
DISPLAY INVISIBLE (250 4375);
FORCEPROP 2 LAST CDS_LIB mstr_discrete
J 0
(300 4175);
PAINT ORANGE (300 4175);
DISPLAY INVISIBLE (300 4175);
FORCEADD OFFPAGE..1
(-675 4175);
FORCEPROP 2 LAST $XR0 102 
J 0
(-927 4175);
DISPLAY 0.638298 (-927 4175);
PAINT MONO (-927 4175);
FORCEPROP 1 LAST OFFPAGE TRUE
J 0
(-350 4050);
DISPLAY 0.872340 (-350 4050);
PAINT GREEN (-350 4050);
DISPLAY INVISIBLE (-350 4050);
FORCEPROP 1 LAST COMMENT_BODY TRUE
J 0
(-550 4075);
DISPLAY 0.872340 (-550 4075);
PAINT GREEN (-550 4075);
DISPLAY INVISIBLE (-550 4075);
FORCEPROP 2 LAST PATH I85
J 0
(-625 4250);
DISPLAY 1.021277 (-625 4250);
PAINT ORANGE (-625 4250);
DISPLAY INVISIBLE (-625 4250);
FORCEPROP 2 LAST CDS_LIB mstr_standard
J 0
(-675 4175);
PAINT ORANGE (-675 4175);
DISPLAY INVISIBLE (-675 4175);
FORCEADD OFFPAGE..2
(1950 3850);
FORCEPROP 2 LAST $XR0 22 
J 0
(2139 3850);
DISPLAY 0.638298 (2139 3850);
PAINT MONO (2139 3850);
FORCEPROP 1 LAST COMMENT_BODY TRUE
J 0
(1905 3755);
DISPLAY 0.872340 (1905 3755);
PAINT GREEN (1905 3755);
DISPLAY INVISIBLE (1905 3755);
FORCEPROP 2 LAST CDS_LIB mstr_standard
J 0
(1950 3850);
PAINT ORANGE (1950 3850);
DISPLAY INVISIBLE (1950 3850);
FORCEPROP 2 LAST PATH I87
J 0
(2125 3925);
DISPLAY 1.021277 (2125 3925);
PAINT ORANGE (2125 3925);
DISPLAY INVISIBLE (2125 3925);
FORCEPROP 1 LAST OFFPAGE TRUE
J 0
(2275 3725);
DISPLAY 0.872340 (2275 3725);
PAINT GREEN (2275 3725);
DISPLAY INVISIBLE (2275 3725);
FORCEADD RES..1
(300 3850);
FORCEPROP 1 LASTPIN (200 3850) $PN 1
J 0
(212 3862);
DISPLAY 0.617021 (212 3862);
PAINT ORANGE (212 3862);
FORCEPROP 1 LAST VALUE 27.4
J 2
(225 3800);
DISPLAY 0.617021 (225 3800);
PAINT SKYBLUE (225 3800);
FORCEPROP 1 LAST WATTAGE 1/16W
J 2
(275 3750);
DISPLAY 0.617021 (275 3750);
PAINT SKYBLUE (275 3750);
FORCEPROP 1 LAST LOCATION R4D7
J 0
(250 3900);
DISPLAY 0.617021 (250 3900);
PAINT AQUA (250 3900);
FORCEPROP 1 LASTPIN (400 3850) $PN 2
J 0
(362 3862);
DISPLAY 0.617021 (362 3862);
PAINT ORANGE (362 3862);
FORCEPROP 1 LAST MATERIAL CHIP
J 0
(350 3800);
DISPLAY 0.617021 (350 3800);
PAINT SKYBLUE (350 3800);
FORCEPROP 1 LAST PACK_TYPE 0402
J 0
(375 3750);
DISPLAY 0.617021 (375 3750);
PAINT SKYBLUE (375 3750);
FORCEPROP 1 LAST TOLERANCE 1%
J 0
(300 3750);
DISPLAY 0.617021 (300 3750);
PAINT SKYBLUE (300 3750);
FORCEPROP 1 LAST PART_NUMBER G21796-182
J 0
(425 3850);
DISPLAY 0.617021 (425 3850);
PAINT BLUE (425 3850);
FORCEPROP 0 LAST ROOM DB1200Z
J 0
(250 4000);
DISPLAY 1.021277 (250 4000);
PAINT ORANGE (250 4000);
DISPLAY INVISIBLE (250 4000);
FORCEPROP 1 LAST PATH I89
J 0
(250 4000);
DISPLAY 0.978723 (250 4000);
PAINT WHITE (250 4000);
DISPLAY INVISIBLE (250 4000);
FORCEPROP 2 LAST CDS_LOCATION R4D7
J 0
(250 3900);
DISPLAY 0.617021 (250 3900);
PAINT AQUA (250 3900);
DISPLAY INVISIBLE (250 3900);
FORCEPROP 2 LAST SEC 1
J 0
(250 4050);
DISPLAY 0.680851 (250 4050);
PAINT MONO (250 4050);
DISPLAY INVISIBLE (250 4050);
FORCEPROP 2 LAST SEC_TYPE 0402
J 0
(250 4050);
DISPLAY 1.021277 (250 4050);
PAINT ORANGE (250 4050);
DISPLAY INVISIBLE (250 4050);
FORCEPROP 2 LAST CDS_LIB mstr_discrete
J 0
(300 3850);
PAINT ORANGE (300 3850);
DISPLAY INVISIBLE (300 3850);
FORCEPROP 0 LAST BOM_COST SYS_CLOCK
J 0
(250 4100);
DISPLAY 1.021277 (250 4100);
PAINT ORANGE (250 4100);
DISPLAY INVISIBLE (250 4100);
FORCEADD RES..1
(-3925 4900);
FORCEPROP 1 LAST VALUE 27.4
J 2
(-4000 4850);
DISPLAY 0.617021 (-4000 4850);
PAINT SKYBLUE (-4000 4850);
FORCEPROP 1 LAST WATTAGE 1/16W
J 2
(-3950 4800);
DISPLAY 0.617021 (-3950 4800);
PAINT SKYBLUE (-3950 4800);
FORCEPROP 1 LAST TOLERANCE 1%
J 0
(-3925 4800);
DISPLAY 0.617021 (-3925 4800);
PAINT SKYBLUE (-3925 4800);
FORCEPROP 1 LASTPIN (-4025 4900) $PN 1
J 0
(-4013 4912);
DISPLAY 0.617021 (-4013 4912);
PAINT ORANGE (-4013 4912);
FORCEPROP 1 LASTPIN (-3825 4900) $PN 2
J 0
(-3863 4912);
DISPLAY 0.617021 (-3863 4912);
PAINT ORANGE (-3863 4912);
FORCEPROP 1 LAST LOCATION R4D23
J 0
(-3975 4950);
DISPLAY 0.617021 (-3975 4950);
PAINT AQUA (-3975 4950);
FORCEPROP 1 LAST PART_NUMBER G21796-182
J 0
(-4075 4750);
DISPLAY 0.617021 (-4075 4750);
PAINT BLUE (-4075 4750);
FORCEPROP 1 LAST MATERIAL CHIP
J 0
(-3875 4850);
DISPLAY 0.617021 (-3875 4850);
PAINT SKYBLUE (-3875 4850);
FORCEPROP 1 LAST PACK_TYPE 0402
J 0
(-3850 4800);
DISPLAY 0.617021 (-3850 4800);
PAINT SKYBLUE (-3850 4800);
FORCEPROP 0 LAST ROOM DB1200Z
J 0
(-3975 5050);
DISPLAY 1.021277 (-3975 5050);
PAINT ORANGE (-3975 5050);
DISPLAY INVISIBLE (-3975 5050);
FORCEPROP 1 LAST PATH I9
J 0
(-3975 5050);
DISPLAY 0.978723 (-3975 5050);
PAINT WHITE (-3975 5050);
DISPLAY INVISIBLE (-3975 5050);
FORCEPROP 2 LAST CDS_LOCATION R4D23
J 0
(-3975 4950);
DISPLAY 0.617021 (-3975 4950);
PAINT AQUA (-3975 4950);
DISPLAY INVISIBLE (-3975 4950);
FORCEPROP 2 LAST CDS_LIB mstr_discrete
J 0
(-3925 4900);
PAINT ORANGE (-3925 4900);
DISPLAY INVISIBLE (-3925 4900);
FORCEPROP 2 LAST SEC 1
J 0
(-3975 5100);
DISPLAY 0.680851 (-3975 5100);
PAINT MONO (-3975 5100);
DISPLAY INVISIBLE (-3975 5100);
FORCEPROP 2 LAST SEC_TYPE 0402
J 0
(-3975 5100);
DISPLAY 1.021277 (-3975 5100);
PAINT ORANGE (-3975 5100);
DISPLAY INVISIBLE (-3975 5100);
FORCEPROP 0 LAST BOM_COST SYS_CLOCK
J 0
(-3975 5150);
DISPLAY 1.021277 (-3975 5150);
PAINT ORANGE (-3975 5150);
DISPLAY INVISIBLE (-3975 5150);
FORCEADD OFFPAGE..1
(-675 3850);
FORCEPROP 2 LAST $XR0 102 
J 0
(-927 3850);
DISPLAY 0.638298 (-927 3850);
PAINT MONO (-927 3850);
FORCEPROP 2 LAST PATH I90
J 0
(-625 3925);
DISPLAY 1.021277 (-625 3925);
PAINT ORANGE (-625 3925);
DISPLAY INVISIBLE (-625 3925);
FORCEPROP 1 LAST COMMENT_BODY TRUE
J 0
(-550 3750);
DISPLAY 0.872340 (-550 3750);
PAINT GREEN (-550 3750);
DISPLAY INVISIBLE (-550 3750);
FORCEPROP 2 LAST CDS_LIB mstr_standard
J 0
(-675 3850);
PAINT ORANGE (-675 3850);
DISPLAY INVISIBLE (-675 3850);
FORCEPROP 1 LAST OFFPAGE TRUE
J 0
(-350 3725);
DISPLAY 0.872340 (-350 3725);
PAINT GREEN (-350 3725);
DISPLAY INVISIBLE (-350 3725);
FORCEADD OFFPAGE..2
(1950 3525);
FORCEPROP 2 LAST $XR0 29 
J 0
(2139 3525);
DISPLAY 0.638298 (2139 3525);
PAINT MONO (2139 3525);
FORCEPROP 1 LAST COMMENT_BODY TRUE
J 0
(1905 3430);
DISPLAY 0.872340 (1905 3430);
PAINT GREEN (1905 3430);
DISPLAY INVISIBLE (1905 3430);
FORCEPROP 2 LAST CDS_LIB mstr_standard
J 0
(1950 3525);
PAINT ORANGE (1950 3525);
DISPLAY INVISIBLE (1950 3525);
FORCEPROP 1 LAST OFFPAGE TRUE
J 0
(2275 3400);
DISPLAY 0.872340 (2275 3400);
PAINT GREEN (2275 3400);
DISPLAY INVISIBLE (2275 3400);
FORCEPROP 2 LAST PATH I92
J 0
(2125 3600);
DISPLAY 1.021277 (2125 3600);
PAINT ORANGE (2125 3600);
DISPLAY INVISIBLE (2125 3600);
FORCEADD RES..1
(300 3525);
FORCEPROP 1 LAST VALUE 27.4
J 2
(225 3475);
DISPLAY 0.617021 (225 3475);
PAINT SKYBLUE (225 3475);
FORCEPROP 1 LASTPIN (200 3525) $PN 1
J 0
(212 3537);
DISPLAY 0.617021 (212 3537);
PAINT ORANGE (212 3537);
FORCEPROP 1 LAST WATTAGE 1/16W
J 2
(275 3425);
DISPLAY 0.617021 (275 3425);
PAINT SKYBLUE (275 3425);
FORCEPROP 1 LASTPIN (400 3525) $PN 2
J 0
(362 3537);
DISPLAY 0.617021 (362 3537);
PAINT ORANGE (362 3537);
FORCEPROP 1 LAST MATERIAL CHIP
J 0
(350 3475);
DISPLAY 0.617021 (350 3475);
PAINT SKYBLUE (350 3475);
FORCEPROP 1 LAST PACK_TYPE 0402
J 0
(375 3425);
DISPLAY 0.617021 (375 3425);
PAINT SKYBLUE (375 3425);
FORCEPROP 1 LAST TOLERANCE 1%
J 0
(300 3425);
DISPLAY 0.617021 (300 3425);
PAINT SKYBLUE (300 3425);
FORCEPROP 1 LAST LOCATION R4D12
J 0
(250 3575);
DISPLAY 0.617021 (250 3575);
PAINT AQUA (250 3575);
FORCEPROP 1 LAST PART_NUMBER G21796-182
J 0
(425 3525);
DISPLAY 0.617021 (425 3525);
PAINT BLUE (425 3525);
FORCEPROP 2 LAST CDS_LIB mstr_discrete
J 0
(300 3525);
PAINT ORANGE (300 3525);
DISPLAY INVISIBLE (300 3525);
FORCEPROP 2 LAST CDS_LOCATION R4D12
J 0
(250 3575);
DISPLAY 0.617021 (250 3575);
PAINT AQUA (250 3575);
DISPLAY INVISIBLE (250 3575);
FORCEPROP 0 LAST BOM_COST SYS_CLOCK
J 0
(250 3775);
DISPLAY 1.021277 (250 3775);
PAINT ORANGE (250 3775);
DISPLAY INVISIBLE (250 3775);
FORCEPROP 2 LAST SEC_TYPE 0402
J 0
(250 3725);
DISPLAY 1.021277 (250 3725);
PAINT ORANGE (250 3725);
DISPLAY INVISIBLE (250 3725);
FORCEPROP 2 LAST SEC 1
J 0
(250 3725);
DISPLAY 0.680851 (250 3725);
PAINT MONO (250 3725);
DISPLAY INVISIBLE (250 3725);
FORCEPROP 1 LAST PATH I94
J 0
(250 3675);
DISPLAY 0.978723 (250 3675);
PAINT WHITE (250 3675);
DISPLAY INVISIBLE (250 3675);
FORCEPROP 0 LAST ROOM DB1200Z
J 0
(250 3675);
DISPLAY 1.021277 (250 3675);
PAINT ORANGE (250 3675);
DISPLAY INVISIBLE (250 3675);
FORCEADD OFFPAGE..1
(-675 3525);
FORCEPROP 2 LAST $XR0 102 
J 0
(-927 3525);
DISPLAY 0.638298 (-927 3525);
PAINT MONO (-927 3525);
FORCEPROP 1 LAST COMMENT_BODY TRUE
J 0
(-550 3425);
DISPLAY 0.872340 (-550 3425);
PAINT GREEN (-550 3425);
DISPLAY INVISIBLE (-550 3425);
FORCEPROP 2 LAST CDS_LIB mstr_standard
J 0
(-675 3525);
PAINT ORANGE (-675 3525);
DISPLAY INVISIBLE (-675 3525);
FORCEPROP 2 LAST PATH I95
J 0
(-625 3600);
DISPLAY 1.021277 (-625 3600);
PAINT ORANGE (-625 3600);
DISPLAY INVISIBLE (-625 3600);
FORCEPROP 1 LAST OFFPAGE TRUE
J 0
(-350 3400);
DISPLAY 0.872340 (-350 3400);
PAINT GREEN (-350 3400);
DISPLAY INVISIBLE (-350 3400);
FORCEADD OFFPAGE..2
(1950 3200);
FORCEPROP 2 LAST $XR0 29 
J 0
(2139 3200);
DISPLAY 0.638298 (2139 3200);
PAINT MONO (2139 3200);
FORCEPROP 2 LAST CDS_LIB mstr_standard
J 0
(1950 3200);
PAINT ORANGE (1950 3200);
DISPLAY INVISIBLE (1950 3200);
FORCEPROP 1 LAST COMMENT_BODY TRUE
J 0
(1905 3105);
DISPLAY 0.872340 (1905 3105);
PAINT GREEN (1905 3105);
DISPLAY INVISIBLE (1905 3105);
FORCEPROP 2 LAST PATH I97
J 0
(2125 3275);
DISPLAY 1.021277 (2125 3275);
PAINT ORANGE (2125 3275);
DISPLAY INVISIBLE (2125 3275);
FORCEPROP 1 LAST OFFPAGE TRUE
J 0
(2275 3075);
DISPLAY 0.872340 (2275 3075);
PAINT GREEN (2275 3075);
DISPLAY INVISIBLE (2275 3075);
FORCEADD RES..1
(300 3200);
FORCEPROP 1 LAST VALUE 27.4
J 2
(225 3150);
DISPLAY 0.617021 (225 3150);
PAINT SKYBLUE (225 3150);
FORCEPROP 1 LASTPIN (200 3200) $PN 1
J 0
(212 3187);
DISPLAY 0.617021 (212 3187);
PAINT ORANGE (212 3187);
FORCEPROP 1 LAST WATTAGE 1/16W
J 2
(275 3100);
DISPLAY 0.617021 (275 3100);
PAINT SKYBLUE (275 3100);
FORCEPROP 1 LAST LOCATION R4D10
J 0
(250 3225);
DISPLAY 0.617021 (250 3225);
PAINT AQUA (250 3225);
FORCEPROP 1 LASTPIN (400 3200) $PN 2
J 0
(362 3187);
DISPLAY 0.617021 (362 3187);
PAINT ORANGE (362 3187);
FORCEPROP 1 LAST MATERIAL CHIP
J 0
(350 3150);
DISPLAY 0.617021 (350 3150);
PAINT SKYBLUE (350 3150);
FORCEPROP 1 LAST PACK_TYPE 0402
J 0
(375 3100);
DISPLAY 0.617021 (375 3100);
PAINT SKYBLUE (375 3100);
FORCEPROP 1 LAST TOLERANCE 1%
J 0
(300 3100);
DISPLAY 0.617021 (300 3100);
PAINT SKYBLUE (300 3100);
FORCEPROP 1 LAST PART_NUMBER G21796-182
J 0
(425 3200);
DISPLAY 0.617021 (425 3200);
PAINT BLUE (425 3200);
FORCEPROP 2 LAST CDS_LOCATION R4D10
J 0
(250 3225);
DISPLAY 0.617021 (250 3225);
PAINT AQUA (250 3225);
DISPLAY INVISIBLE (250 3225);
FORCEPROP 0 LAST ROOM DB1200Z
J 0
(250 3325);
DISPLAY 1.021277 (250 3325);
PAINT ORANGE (250 3325);
DISPLAY INVISIBLE (250 3325);
FORCEPROP 0 LAST BOM_COST SYS_CLOCK
J 0
(250 3425);
DISPLAY 1.021277 (250 3425);
PAINT ORANGE (250 3425);
DISPLAY INVISIBLE (250 3425);
FORCEPROP 2 LAST SEC_TYPE 0402
J 0
(250 3400);
DISPLAY 1.021277 (250 3400);
PAINT ORANGE (250 3400);
DISPLAY INVISIBLE (250 3400);
FORCEPROP 2 LAST SEC 1
J 0
(250 3400);
DISPLAY 0.680851 (250 3400);
PAINT MONO (250 3400);
DISPLAY INVISIBLE (250 3400);
FORCEPROP 1 LAST PATH I99
J 0
(250 3350);
DISPLAY 0.978723 (250 3350);
PAINT WHITE (250 3350);
DISPLAY INVISIBLE (250 3350);
FORCEPROP 2 LAST CDS_LIB mstr_discrete
J 0
(300 3200);
PAINT ORANGE (300 3200);
DISPLAY INVISIBLE (300 3200);
FORCEADD DNS..2
(-3320 4070);
PAINT RED (-3320 4070);
FORCEPROP 1 LAST COMMENT_BODY TRUE
R 1
J 0
(-3245 3845);
DISPLAY 0.872340 (-3245 3845);
PAINT GREEN (-3245 3845);
DISPLAY INVISIBLE (-3245 3845);
FORCEPROP 2 LAST CDS_LIB mstr_misc
J 0
(-3320 4070);
PAINT ORANGE (-3320 4070);
DISPLAY INVISIBLE (-3320 4070);
FORCEADD DNS..2
(-3320 3745);
PAINT RED (-3320 3745);
FORCEPROP 1 LAST COMMENT_BODY TRUE
R 1
J 0
(-3245 3520);
DISPLAY 0.872340 (-3245 3520);
PAINT GREEN (-3245 3520);
DISPLAY INVISIBLE (-3245 3520);
FORCEPROP 2 LAST CDS_LIB mstr_misc
J 0
(-3320 3745);
PAINT ORANGE (-3320 3745);
DISPLAY INVISIBLE (-3320 3745);
FORCEADD DESIGN_NOTE..1
(-200 5350);
FORCEPROP 0 LAST L2 REQUIRED WITH -ZL VERSION
J 0
(-400 5150);
DISPLAY 1.021277 (-400 5150);
PAINT ORANGE (-400 5150);
FORCEPROP 0 LAST L1 PARALLEL RESISTORS ARE NOT
J 0
(-400 5225);
DISPLAY 1.021277 (-400 5225);
PAINT ORANGE (-400 5225);
FORCEPROP 0 LAST L3 ONLY REQUIRED WITH -L VERSION
J 0
(-400 5075);
DISPLAY 1.021277 (-400 5075);
PAINT ORANGE (-400 5075);
FORCEPROP 1 LAST COMMENT_BODY TRUE
J 0
(-175 5450);
DISPLAY 0.978723 (-175 5450);
PAINT ORANGE (-175 5450);
DISPLAY INVISIBLE (-175 5450);
FORCEPROP 2 LAST CDS_LIB mstr_symbols
J 0
(-200 5350);
PAINT MONO (-200 5350);
DISPLAY INVISIBLE (-200 5350);
FORCEADD DNS..2
(-3320 4795);
PAINT RED (-3320 4795);
FORCEPROP 1 LAST COMMENT_BODY TRUE
R 1
J 0
(-3245 4570);
DISPLAY 0.872340 (-3245 4570);
PAINT GREEN (-3245 4570);
DISPLAY INVISIBLE (-3245 4570);
FORCEPROP 2 LAST CDS_LIB mstr_misc
J 0
(-3320 4795);
PAINT ORANGE (-3320 4795);
DISPLAY INVISIBLE (-3320 4795);
FORCEADD CAD_NOTE..1
(1200 5300);
FORCEPROP 0 LAST L1 PLACE RESISTORS CLOSE TO CLK
J 0
(1050 5175);
DISPLAY 1.021277 (1050 5175);
PAINT ORANGE (1050 5175);
FORCEPROP 0 LAST L2 SOURCE WITHIN 0.5 INCHES
J 0
(1050 5100);
DISPLAY 1.021277 (1050 5100);
PAINT ORANGE (1050 5100);
FORCEPROP 1 LAST COMMENT_BODY TRUE
J 0
(1225 5400);
DISPLAY 0.978723 (1225 5400);
PAINT ORANGE (1225 5400);
DISPLAY INVISIBLE (1225 5400);
FORCEPROP 2 LAST CDS_LIB mstr_symbols
J 0
(1200 5300);
PAINT ORANGE (1200 5300);
DISPLAY INVISIBLE (1200 5300);
FORCEADD DNS..2
(-3320 3095);
PAINT RED (-3320 3095);
FORCEPROP 1 LAST COMMENT_BODY TRUE
R 1
J 0
(-3245 2870);
DISPLAY 0.872340 (-3245 2870);
PAINT GREEN (-3245 2870);
DISPLAY INVISIBLE (-3245 2870);
FORCEPROP 2 LAST CDS_LIB mstr_misc
J 0
(-3320 3095);
PAINT ORANGE (-3320 3095);
DISPLAY INVISIBLE (-3320 3095);
FORCEADD DNS..2
(-3320 2770);
PAINT RED (-3320 2770);
FORCEPROP 1 LAST COMMENT_BODY TRUE
R 1
J 0
(-3245 2545);
DISPLAY 0.872340 (-3245 2545);
PAINT GREEN (-3245 2545);
DISPLAY INVISIBLE (-3245 2545);
FORCEPROP 2 LAST CDS_LIB mstr_misc
J 0
(-3320 2770);
PAINT ORANGE (-3320 2770);
DISPLAY INVISIBLE (-3320 2770);
FORCEADD DNS..2
(-3320 2445);
PAINT RED (-3320 2445);
FORCEPROP 1 LAST COMMENT_BODY TRUE
R 1
J 0
(-3245 2220);
DISPLAY 0.872340 (-3245 2220);
PAINT GREEN (-3245 2220);
DISPLAY INVISIBLE (-3245 2220);
FORCEPROP 2 LAST CDS_LIB mstr_misc
J 0
(-3320 2445);
PAINT ORANGE (-3320 2445);
DISPLAY INVISIBLE (-3320 2445);
FORCEADD DNS..2
(-3320 2120);
PAINT RED (-3320 2120);
FORCEPROP 1 LAST COMMENT_BODY TRUE
R 1
J 0
(-3245 1895);
DISPLAY 0.872340 (-3245 1895);
PAINT GREEN (-3245 1895);
DISPLAY INVISIBLE (-3245 1895);
FORCEPROP 2 LAST CDS_LIB mstr_misc
J 0
(-3320 2120);
PAINT ORANGE (-3320 2120);
DISPLAY INVISIBLE (-3320 2120);
FORCEADD DNS..2
(-3320 1795);
PAINT RED (-3320 1795);
FORCEPROP 1 LAST COMMENT_BODY TRUE
R 1
J 0
(-3245 1570);
DISPLAY 0.872340 (-3245 1570);
PAINT GREEN (-3245 1570);
DISPLAY INVISIBLE (-3245 1570);
FORCEPROP 2 LAST CDS_LIB mstr_misc
J 0
(-3320 1795);
PAINT ORANGE (-3320 1795);
DISPLAY INVISIBLE (-3320 1795);
FORCEADD DNS..2
(-3320 1470);
PAINT RED (-3320 1470);
FORCEPROP 1 LAST COMMENT_BODY TRUE
R 1
J 0
(-3245 1245);
DISPLAY 0.872340 (-3245 1245);
PAINT GREEN (-3245 1245);
DISPLAY INVISIBLE (-3245 1245);
FORCEPROP 2 LAST CDS_LIB mstr_misc
J 0
(-3320 1470);
PAINT ORANGE (-3320 1470);
DISPLAY INVISIBLE (-3320 1470);
FORCEADD DNS..2
(-3320 1145);
PAINT RED (-3320 1145);
FORCEPROP 1 LAST COMMENT_BODY TRUE
R 1
J 0
(-3245 920);
DISPLAY 0.872340 (-3245 920);
PAINT GREEN (-3245 920);
DISPLAY INVISIBLE (-3245 920);
FORCEPROP 2 LAST CDS_LIB mstr_misc
J 0
(-3320 1145);
PAINT ORANGE (-3320 1145);
DISPLAY INVISIBLE (-3320 1145);
FORCEADD DNS..2
(1030 4720);
PAINT RED (1030 4720);
FORCEPROP 1 LAST COMMENT_BODY TRUE
R 1
J 0
(1105 4495);
DISPLAY 0.872340 (1105 4495);
PAINT GREEN (1105 4495);
DISPLAY INVISIBLE (1105 4495);
FORCEPROP 2 LAST CDS_LIB mstr_misc
J 0
(1030 4720);
PAINT ORANGE (1030 4720);
DISPLAY INVISIBLE (1030 4720);
FORCEADD DNS..2
(-3320 3420);
PAINT RED (-3320 3420);
FORCEPROP 1 LAST COMMENT_BODY TRUE
R 1
J 0
(-3245 3195);
DISPLAY 0.872340 (-3245 3195);
PAINT GREEN (-3245 3195);
DISPLAY INVISIBLE (-3245 3195);
FORCEPROP 2 LAST CDS_LIB mstr_misc
J 0
(-3320 3420);
PAINT ORANGE (-3320 3420);
DISPLAY INVISIBLE (-3320 3420);
FORCEADD DNS..2
(1055 4395);
PAINT RED (1055 4395);
FORCEPROP 1 LAST COMMENT_BODY TRUE
R 1
J 0
(1130 4170);
DISPLAY 0.872340 (1130 4170);
PAINT GREEN (1130 4170);
DISPLAY INVISIBLE (1130 4170);
FORCEPROP 2 LAST CDS_LIB mstr_misc
J 0
(1055 4395);
PAINT ORANGE (1055 4395);
DISPLAY INVISIBLE (1055 4395);
FORCEADD DNS..2
(1030 4070);
PAINT RED (1030 4070);
FORCEPROP 1 LAST COMMENT_BODY TRUE
R 1
J 0
(1105 3845);
DISPLAY 0.872340 (1105 3845);
PAINT GREEN (1105 3845);
DISPLAY INVISIBLE (1105 3845);
FORCEPROP 2 LAST CDS_LIB mstr_misc
J 0
(1030 4070);
PAINT ORANGE (1030 4070);
DISPLAY INVISIBLE (1030 4070);
FORCEADD DNS..2
(1055 3745);
PAINT RED (1055 3745);
FORCEPROP 1 LAST COMMENT_BODY TRUE
R 1
J 0
(1130 3520);
DISPLAY 0.872340 (1130 3520);
PAINT GREEN (1130 3520);
DISPLAY INVISIBLE (1130 3520);
FORCEPROP 2 LAST CDS_LIB mstr_misc
J 0
(1055 3745);
PAINT ORANGE (1055 3745);
DISPLAY INVISIBLE (1055 3745);
FORCEADD DNS..2
(1055 3420);
PAINT RED (1055 3420);
FORCEPROP 1 LAST COMMENT_BODY TRUE
R 1
J 0
(1130 3195);
DISPLAY 0.872340 (1130 3195);
PAINT GREEN (1130 3195);
DISPLAY INVISIBLE (1130 3195);
FORCEPROP 2 LAST CDS_LIB mstr_misc
J 0
(1055 3420);
PAINT ORANGE (1055 3420);
DISPLAY INVISIBLE (1055 3420);
FORCEADD DNS..2
(1080 3095);
PAINT RED (1080 3095);
FORCEPROP 1 LAST COMMENT_BODY TRUE
R 1
J 0
(1155 2870);
DISPLAY 0.872340 (1155 2870);
PAINT GREEN (1155 2870);
DISPLAY INVISIBLE (1155 2870);
FORCEPROP 2 LAST CDS_LIB mstr_misc
J 0
(1080 3095);
PAINT ORANGE (1080 3095);
DISPLAY INVISIBLE (1080 3095);
FORCEADD DNS..2
(1055 2770);
PAINT RED (1055 2770);
FORCEPROP 1 LAST COMMENT_BODY TRUE
R 1
J 0
(1130 2545);
DISPLAY 0.872340 (1130 2545);
PAINT GREEN (1130 2545);
DISPLAY INVISIBLE (1130 2545);
FORCEPROP 2 LAST CDS_LIB mstr_misc
J 0
(1055 2770);
PAINT ORANGE (1055 2770);
DISPLAY INVISIBLE (1055 2770);
FORCEADD DNS..2
(1055 2445);
PAINT RED (1055 2445);
FORCEPROP 1 LAST COMMENT_BODY TRUE
R 1
J 0
(1130 2220);
DISPLAY 0.872340 (1130 2220);
PAINT GREEN (1130 2220);
DISPLAY INVISIBLE (1130 2220);
FORCEPROP 2 LAST CDS_LIB mstr_misc
J 0
(1055 2445);
PAINT ORANGE (1055 2445);
DISPLAY INVISIBLE (1055 2445);
FORCEADD DNS..2
(1055 2120);
PAINT RED (1055 2120);
FORCEPROP 1 LAST COMMENT_BODY TRUE
R 1
J 0
(1130 1895);
DISPLAY 0.872340 (1130 1895);
PAINT GREEN (1130 1895);
DISPLAY INVISIBLE (1130 1895);
FORCEPROP 2 LAST CDS_LIB mstr_misc
J 0
(1055 2120);
PAINT ORANGE (1055 2120);
DISPLAY INVISIBLE (1055 2120);
FORCEADD DNS..2
(1055 1795);
PAINT RED (1055 1795);
FORCEPROP 1 LAST COMMENT_BODY TRUE
R 1
J 0
(1130 1570);
DISPLAY 0.872340 (1130 1570);
PAINT GREEN (1130 1570);
DISPLAY INVISIBLE (1130 1570);
FORCEPROP 2 LAST CDS_LIB mstr_misc
J 0
(1055 1795);
PAINT ORANGE (1055 1795);
DISPLAY INVISIBLE (1055 1795);
FORCEADD DNS..2
(1055 1470);
PAINT RED (1055 1470);
FORCEPROP 1 LAST COMMENT_BODY TRUE
R 1
J 0
(1130 1245);
DISPLAY 0.872340 (1130 1245);
PAINT GREEN (1130 1245);
DISPLAY INVISIBLE (1130 1245);
FORCEPROP 2 LAST CDS_LIB mstr_misc
J 0
(1055 1470);
PAINT ORANGE (1055 1470);
DISPLAY INVISIBLE (1055 1470);
FORCEADD DNS..2
(-3295 4420);
PAINT RED (-3295 4420);
FORCEPROP 1 LAST COMMENT_BODY TRUE
R 1
J 0
(-3220 4195);
DISPLAY 0.872340 (-3220 4195);
PAINT GREEN (-3220 4195);
DISPLAY INVISIBLE (-3220 4195);
FORCEPROP 2 LAST CDS_LIB mstr_misc
J 0
(-3295 4420);
PAINT ORANGE (-3295 4420);
DISPLAY INVISIBLE (-3295 4420);
FORCEADD DNS..2
(1055 1145);
PAINT RED (1055 1145);
FORCEPROP 1 LAST COMMENT_BODY TRUE
R 1
J 0
(1130 920);
DISPLAY 0.872340 (1130 920);
PAINT GREEN (1130 920);
DISPLAY INVISIBLE (1130 920);
FORCEPROP 2 LAST CDS_LIB mstr_misc
J 0
(1055 1145);
PAINT ORANGE (1055 1145);
DISPLAY INVISIBLE (1055 1145);
FORCEADD INTEL_CORP_BPAGE..1
(2650 500);
FORCEPROP 1 LAST CDS_CON_LAST_MODIFIED Tue Dec 01 11:51:51 2015
J 0
(1225 825);
PAINT ORANGE (1225 825);
DISPLAY INVISIBLE (1225 825);
FORCEPROP 1 LAST CUSTOM_TXT_CDS <CURRENT_DESIGN_SHEET> OF <TOTAL_DESIGN_SHEETS>
J 0
(2150 525);
PAINT GREEN (2150 525);
FORCEPROP 1 LAST CUSTOM_TXT_CDS <CON_LAST_MODIFIED>
J 0
(725 850);
PAINT GREEN (725 850);
FORCEPROP 2 LAST CUSTOM_TXT_CDS <XR_PAGE_TITLE>
J 0
(-5240 5750);
DISPLAY 0.638298 (-5240 5750);
PAINT PINK (-5240 5750);
DISPLAY INVISIBLE (-5240 5750);
FORCEPROP 1 LAST SCH_TITLE DB1200ZL CLOCK TERMINATION
J 0
(-5300 550);
DISPLAY 1.212766 (-5300 550);
PAINT ORANGE (-5300 550);
FORCEPROP 1 LAST SCH_ADDRESS1 2200 Mission College Blvd.
J 0
(-1325 625);
DISPLAY 0.617021 (-1325 625);
PAINT GREEN (-1325 625);
FORCEPROP 1 LAST SCH_ADDRESS2 P.O. BOX 58119
J 0
(-1325 575);
DISPLAY 0.617021 (-1325 575);
PAINT GREEN (-1325 575);
FORCEPROP 1 LAST SCH_ADDRESS3 Santa Clara, CA 95052-8119
J 0
(-1325 525);
DISPLAY 0.617021 (-1325 525);
PAINT GREEN (-1325 525);
FORCEPROP 1 LAST SCH_NUMBER H4694802
J 0
(1350 650);
DISPLAY 1.212766 (1350 650);
PAINT YELLOW (1350 650);
FORCEPROP 1 LAST SCH_DEPT BESD
J 1
(-1800 600);
DISPLAY 1.212766 (-1800 600);
PAINT YELLOW (-1800 600);
FORCEPROP 1 LAST SCH_REV 2.420
J 0
(2400 650);
DISPLAY 0.978723 (2400 650);
PAINT YELLOW (2400 650);
FORCEPROP 2 LAST PAGE_BORDER TRUE
J 0
(-5240 5750);
DISPLAY 0.617021 (-5240 5750);
PAINT PINK (-5240 5750);
DISPLAY INVISIBLE (-5240 5750);
FORCEPROP 1 LAST COMMENT_BODY TRUE
J 0
(2662 512);
DISPLAY 0.468085 (2662 512);
PAINT GREEN (2662 512);
DISPLAY INVISIBLE (2662 512);
FORCEPROP 2 LAST CDS_LIB mstr_symbols
J 0
(2650 500);
PAINT MONO (2650 500);
DISPLAY INVISIBLE (2650 500);
FORCEPROP 2 LAST CDS_XR_PAGE_TITLE CR-103 : @BASEBOARD_FAB2_LIB.BASEBOARD_FAB2(SCH_1):PAGE103
J 0
(-5240 5750);
DISPLAY 0.638298 (-5240 5750);
PAINT PINK (-5240 5750);
DISPLAY INVISIBLE (-5240 5750);
WIRE 16 -1 (-3225 4075)(-2800 4075);
WIRE 16 -1 (-2800 4075)(-2800 4025);
WIRE 16 -1 (-3225 3750)(-2800 3750);
WIRE 16 -1 (-2800 3750)(-2800 3700);
WIRE 16 -1 (-3225 3425)(-2800 3425);
WIRE 16 -1 (-2800 3425)(-2800 3375);
WIRE 16 -1 (-3225 3100)(-2800 3100);
WIRE 16 -1 (-2800 3100)(-2800 3050);
WIRE 16 -1 (-3225 2775)(-2800 2775);
WIRE 16 -1 (-2800 2775)(-2800 2725);
WIRE 16 -1 (-3225 2450)(-2800 2450);
WIRE 16 -1 (-2800 2450)(-2800 2400);
WIRE 16 -1 (-3225 2125)(-2800 2125);
WIRE 16 -1 (-2800 2125)(-2800 2075);
WIRE 16 -1 (-3225 1800)(-2800 1800);
WIRE 16 -1 (-2800 1800)(-2800 1750);
WIRE 16 -1 (-3225 1475)(-2800 1475);
WIRE 16 -1 (-2800 1475)(-2800 1425);
WIRE 16 -1 (-3225 1150)(-2800 1150);
WIRE 16 -1 (-2800 1150)(-2800 1100);
WIRE 16 -1 (1125 4725)(1550 4725);
WIRE 16 -1 (1550 4725)(1550 4675);
WIRE 16 -1 (1150 4400)(1575 4400);
WIRE 16 -1 (1575 4400)(1575 4350);
WIRE 16 -1 (1125 4075)(1550 4075);
WIRE 16 -1 (1550 4075)(1550 4025);
WIRE 16 -1 (1150 3750)(1575 3750);
WIRE 16 -1 (1575 3750)(1575 3700);
WIRE 16 -1 (1150 3425)(1575 3425);
WIRE 16 -1 (1575 3425)(1575 3375);
WIRE 16 -1 (1175 3100)(1600 3100);
WIRE 16 -1 (1600 3100)(1600 3050);
WIRE 16 -1 (1150 2775)(1575 2775);
WIRE 16 -1 (1575 2775)(1575 2725);
WIRE 16 -1 (1150 2450)(1575 2450);
WIRE 16 -1 (1575 2450)(1575 2400);
WIRE 16 -1 (1150 2125)(1575 2125);
WIRE 16 -1 (1575 2125)(1575 2075);
WIRE 16 -1 (1150 1800)(1575 1800);
WIRE 16 -1 (1575 1800)(1575 1750);
WIRE 16 -1 (1150 1475)(1575 1475);
WIRE 16 -1 (1575 1475)(1575 1425);
WIRE 16 -1 (1150 1150)(1575 1150);
WIRE 16 -1 (1575 1150)(1575 1100);
WIRE 16 -1 (-3200 4425)(-2775 4425);
WIRE 16 -1 (-2775 4425)(-2775 4375);
WIRE 16 -1 (-3225 4800)(-2800 4800);
WIRE 16 -1 (-2800 4800)(-2800 4750);
WIRE 16 -1 (1900 4175)(775 4175);
FORCEPROP 2 LAST SIG_NAME CLK_100M_CPU0_RC_REFCLK0_DP
J 0
(1275 4185);
DISPLAY 0.617021 (1275 4185);
PAINT ORANGE (1275 4185);
WIRE 16 -1 (775 4175)(400 4175);
WIRE 16 -1 (775 4075)(775 4175);
WIRE 16 -1 (925 4075)(775 4075);
WIRE 16 -1 (1900 4500)(800 4500);
FORCEPROP 2 LAST SIG_NAME CLK_100M_CPU0_RC_REFCLK1_DN
J 0
(1275 4510);
DISPLAY 0.617021 (1275 4510);
PAINT ORANGE (1275 4510);
WIRE 16 -1 (800 4400)(800 4500);
WIRE 16 -1 (800 4500)(400 4500);
WIRE 16 -1 (950 4400)(800 4400);
WIRE 16 -1 (1900 4825)(775 4825);
FORCEPROP 2 LAST SIG_NAME CLK_100M_CPU0_RC_REFCLK1_DP
J 0
(1275 4835);
DISPLAY 0.617021 (1275 4835);
PAINT ORANGE (1275 4835);
WIRE 16 -1 (775 4725)(775 4825);
WIRE 16 -1 (775 4825)(400 4825);
WIRE 16 -1 (925 4725)(775 4725);
WIRE 16 -1 (1900 2225)(800 2225);
FORCEPROP 2 LAST SIG_NAME CLK_100M_CPU0_BCLK1_DP
J 0
(1275 2235);
DISPLAY 0.617021 (1275 2235);
PAINT ORANGE (1275 2235);
WIRE 16 -1 (800 2125)(800 2225);
WIRE 16 -1 (800 2225)(400 2225);
WIRE 16 -1 (950 2125)(800 2125);
WIRE 16 -1 (1900 2550)(800 2550);
FORCEPROP 2 LAST SIG_NAME CLK_100M_CPU0_BCLK2_DN
J 0
(1275 2560);
DISPLAY 0.617021 (1275 2560);
PAINT ORANGE (1275 2560);
WIRE 16 -1 (800 2450)(800 2550);
WIRE 16 -1 (800 2550)(400 2550);
WIRE 16 -1 (950 2450)(800 2450);
WIRE 16 -1 (1900 2875)(800 2875);
FORCEPROP 2 LAST SIG_NAME CLK_100M_CPU0_BCLK2_DP
J 0
(1275 2885);
DISPLAY 0.617021 (1275 2885);
PAINT ORANGE (1275 2885);
WIRE 16 -1 (800 2775)(800 2875);
WIRE 16 -1 (800 2875)(400 2875);
WIRE 16 -1 (950 2775)(800 2775);
WIRE 16 -1 (1900 3200)(825 3200);
FORCEPROP 2 LAST SIG_NAME CLK_100M_CPU0_PE_REFCLK_DN
J 0
(1275 3210);
DISPLAY 0.617021 (1275 3210);
PAINT ORANGE (1275 3210);
WIRE 16 -1 (825 3100)(825 3200);
WIRE 16 -1 (825 3200)(400 3200);
WIRE 16 -1 (975 3100)(825 3100);
WIRE 16 -1 (1900 3525)(800 3525);
FORCEPROP 2 LAST SIG_NAME CLK_100M_CPU0_PE_REFCLK_DP
J 0
(1275 3535);
DISPLAY 0.617021 (1275 3535);
PAINT ORANGE (1275 3535);
WIRE 16 -1 (800 3425)(800 3525);
WIRE 16 -1 (800 3525)(400 3525);
WIRE 16 -1 (950 3425)(800 3425);
WIRE 16 -1 (1900 3850)(800 3850);
FORCEPROP 2 LAST SIG_NAME CLK_100M_CPU0_RC_REFCLK0_DN
J 0
(1275 3860);
DISPLAY 0.617021 (1275 3860);
PAINT ORANGE (1275 3860);
WIRE 16 -1 (800 3750)(800 3850);
WIRE 16 -1 (800 3850)(400 3850);
WIRE 16 -1 (950 3750)(800 3750);
WIRE 16 -1 (800 1250)(1900 1250);
FORCEPROP 2 LAST SIG_NAME CLK_100M_CPU0_BCLK0_DN
J 0
(1275 1260);
DISPLAY 0.617021 (1275 1260);
PAINT ORANGE (1275 1260);
WIRE 16 -1 (800 1150)(800 1250);
WIRE 16 -1 (400 1250)(800 1250);
WIRE 16 -1 (950 1150)(800 1150);
WIRE 16 -1 (800 1575)(1900 1575);
FORCEPROP 2 LAST SIG_NAME CLK_100M_CPU0_BCLK0_DP
J 0
(1275 1585);
DISPLAY 0.617021 (1275 1585);
PAINT ORANGE (1275 1585);
WIRE 16 -1 (800 1475)(800 1575);
WIRE 16 -1 (400 1575)(800 1575);
WIRE 16 -1 (950 1475)(800 1475);
WIRE 16 -1 (800 1900)(1900 1900);
FORCEPROP 2 LAST SIG_NAME CLK_100M_CPU0_BCLK1_DN
J 0
(1275 1910);
DISPLAY 0.617021 (1275 1910);
PAINT ORANGE (1275 1910);
WIRE 16 -1 (800 1800)(800 1900);
WIRE 16 -1 (400 1900)(800 1900);
WIRE 16 -1 (950 1800)(800 1800);
WIRE 16 -1 (200 3200)(-625 3200);
FORCEPROP 2 LAST SIG_NAME CLK_100M_CPU0_PE_REFCLK_R_DN
J 0
(-610 3210);
DISPLAY 0.617021 (-610 3210);
PAINT ORANGE (-610 3210);
WIRE 16 -1 (200 2875)(-625 2875);
FORCEPROP 2 LAST SIG_NAME CLK_100M_CPU0_BCLK2_R_DP
J 0
(-585 2885);
DISPLAY 0.617021 (-585 2885);
PAINT ORANGE (-585 2885);
WIRE 16 -1 (200 2550)(-625 2550);
FORCEPROP 2 LAST SIG_NAME CLK_100M_CPU0_BCLK2_R_DN
J 0
(-585 2560);
DISPLAY 0.617021 (-585 2560);
PAINT ORANGE (-585 2560);
WIRE 16 -1 (200 2225)(-625 2225);
FORCEPROP 2 LAST SIG_NAME CLK_100M_CPU0_BCLK1_R_DP
J 0
(-585 2235);
DISPLAY 0.617021 (-585 2235);
PAINT ORANGE (-585 2235);
WIRE 16 -1 (200 1900)(-625 1900);
FORCEPROP 2 LAST SIG_NAME CLK_100M_CPU0_BCLK1_R_DN
J 0
(-585 1910);
DISPLAY 0.617021 (-585 1910);
PAINT ORANGE (-585 1910);
WIRE 16 -1 (200 1250)(-625 1250);
FORCEPROP 2 LAST SIG_NAME CLK_100M_CPU0_BCLK0_R_DN
J 0
(-585 1260);
DISPLAY 0.617021 (-585 1260);
PAINT ORANGE (-585 1260);
WIRE 16 -1 (200 1575)(-625 1575);
FORCEPROP 2 LAST SIG_NAME CLK_100M_CPU0_BCLK0_R_DP
J 0
(-585 1585);
DISPLAY 0.617021 (-585 1585);
PAINT ORANGE (-585 1585);
WIRE 16 -1 (200 4825)(-625 4825);
FORCEPROP 2 LAST SIG_NAME CLK_100M_CPU0_RC_REFCLK1_R_DP
J 0
(-610 4835);
DISPLAY 0.617021 (-610 4835);
PAINT ORANGE (-610 4835);
WIRE 16 -1 (200 4500)(-625 4500);
FORCEPROP 2 LAST SIG_NAME CLK_100M_CPU0_RC_REFCLK1_R_DN
J 0
(-585 4510);
DISPLAY 0.617021 (-585 4510);
PAINT ORANGE (-585 4510);
WIRE 16 -1 (200 4175)(-625 4175);
FORCEPROP 2 LAST SIG_NAME CLK_100M_CPU0_RC_REFCLK0_R_DP
J 0
(-610 4185);
DISPLAY 0.617021 (-610 4185);
PAINT ORANGE (-610 4185);
WIRE 16 -1 (200 3850)(-625 3850);
FORCEPROP 2 LAST SIG_NAME CLK_100M_CPU0_RC_REFCLK0_R_DN
J 0
(-610 3860);
DISPLAY 0.617021 (-610 3860);
PAINT ORANGE (-610 3860);
WIRE 16 -1 (200 3525)(-625 3525);
FORCEPROP 2 LAST SIG_NAME CLK_100M_CPU0_PE_REFCLK_R_DP
J 0
(-610 3535);
DISPLAY 0.617021 (-610 3535);
PAINT ORANGE (-610 3535);
WIRE 16 -1 (-3825 4175)(-3575 4175);
WIRE 16 -1 (-3575 4175)(-2275 4175);
FORCEPROP 2 LAST SIG_NAME CLK_100M_CPU1_RC_REFCLK0_DP
J 0
(-2950 4185);
DISPLAY 0.617021 (-2950 4185);
PAINT ORANGE (-2950 4185);
WIRE 16 -1 (-3575 4075)(-3575 4175);
WIRE 16 -1 (-3425 4075)(-3575 4075);
WIRE 16 -1 (-3550 4525)(-2275 4525);
WIRE 16 -1 (-3550 4425)(-3550 4525);
WIRE 16 -1 (-3825 4525)(-3550 4525);
FORCEPROP 0 LAST SIG_NAME CLK_100M_CPU1_RC_REFCLK1_DN
J 0
(-2950 4535);
DISPLAY 0.617021 (-2950 4535);
PAINT ORANGE (-2950 4535);
WIRE 16 -1 (-3400 4425)(-3550 4425);
WIRE 16 -1 (-3575 4900)(-2275 4900);
WIRE 16 -1 (-3575 4800)(-3575 4900);
WIRE 16 -1 (-3825 4900)(-3575 4900);
FORCEPROP 0 LAST SIG_NAME CLK_100M_CPU1_RC_REFCLK1_DP
J 0
(-2950 4910);
DISPLAY 0.617021 (-2950 4910);
PAINT ORANGE (-2950 4910);
WIRE 16 -1 (-3425 4800)(-3575 4800);
WIRE 16 -1 (-3575 2225)(-2275 2225);
FORCEPROP 2 LAST SIG_NAME CLK_100M_CPU1_BCLK1_DP
J 0
(-2950 2235);
DISPLAY 0.617021 (-2950 2235);
PAINT ORANGE (-2950 2235);
WIRE 16 -1 (-3575 2125)(-3575 2225);
WIRE 16 -1 (-3825 2225)(-3575 2225);
WIRE 16 -1 (-3425 2125)(-3575 2125);
WIRE 16 -1 (-3575 2550)(-2275 2550);
FORCEPROP 2 LAST SIG_NAME CLK_100M_CPU1_BCLK2_DN
J 0
(-2950 2560);
DISPLAY 0.617021 (-2950 2560);
PAINT ORANGE (-2950 2560);
WIRE 16 -1 (-3575 2450)(-3575 2550);
WIRE 16 -1 (-3825 2550)(-3575 2550);
WIRE 16 -1 (-3425 2450)(-3575 2450);
WIRE 16 -1 (-3575 2875)(-2275 2875);
FORCEPROP 2 LAST SIG_NAME CLK_100M_CPU1_BCLK2_DP
J 0
(-2950 2885);
DISPLAY 0.617021 (-2950 2885);
PAINT ORANGE (-2950 2885);
WIRE 16 -1 (-3575 2775)(-3575 2875);
WIRE 16 -1 (-3825 2875)(-3575 2875);
WIRE 16 -1 (-3425 2775)(-3575 2775);
WIRE 16 -1 (-3575 3200)(-2275 3200);
FORCEPROP 2 LAST SIG_NAME CLK_100M_CPU1_PE_REFCLK_DN
J 0
(-2950 3210);
DISPLAY 0.617021 (-2950 3210);
PAINT ORANGE (-2950 3210);
WIRE 16 -1 (-3575 3100)(-3575 3200);
WIRE 16 -1 (-3825 3200)(-3575 3200);
WIRE 16 -1 (-3425 3100)(-3575 3100);
WIRE 16 -1 (-3575 3525)(-2275 3525);
FORCEPROP 2 LAST SIG_NAME CLK_100M_CPU1_PE_REFCLK_DP
J 0
(-2950 3535);
DISPLAY 0.617021 (-2950 3535);
PAINT ORANGE (-2950 3535);
WIRE 16 -1 (-3575 3425)(-3575 3525);
WIRE 16 -1 (-3825 3525)(-3575 3525);
WIRE 16 -1 (-3425 3425)(-3575 3425);
WIRE 16 -1 (-3575 3850)(-2275 3850);
FORCEPROP 2 LAST SIG_NAME CLK_100M_CPU1_RC_REFCLK0_DN
J 0
(-2950 3860);
DISPLAY 0.617021 (-2950 3860);
PAINT ORANGE (-2950 3860);
WIRE 16 -1 (-3575 3750)(-3575 3850);
WIRE 16 -1 (-3825 3850)(-3575 3850);
WIRE 16 -1 (-3425 3750)(-3575 3750);
WIRE 16 -1 (-3575 1250)(-2275 1250);
FORCEPROP 2 LAST SIG_NAME CLK_100M_CPU1_BCLK0_DN
J 0
(-2950 1260);
DISPLAY 0.617021 (-2950 1260);
PAINT ORANGE (-2950 1260);
WIRE 16 -1 (-3575 1150)(-3575 1250);
WIRE 16 -1 (-3825 1250)(-3575 1250);
WIRE 16 -1 (-3425 1150)(-3575 1150);
WIRE 16 -1 (-3575 1575)(-2275 1575);
FORCEPROP 2 LAST SIG_NAME CLK_100M_CPU1_BCLK0_DP
J 0
(-2950 1585);
DISPLAY 0.617021 (-2950 1585);
PAINT ORANGE (-2950 1585);
WIRE 16 -1 (-3575 1475)(-3575 1575);
WIRE 16 -1 (-3825 1575)(-3575 1575);
WIRE 16 -1 (-3425 1475)(-3575 1475);
WIRE 16 -1 (-3575 1900)(-2275 1900);
FORCEPROP 2 LAST SIG_NAME CLK_100M_CPU1_BCLK1_DN
J 0
(-2950 1910);
DISPLAY 0.617021 (-2950 1910);
PAINT ORANGE (-2950 1910);
WIRE 16 -1 (-3575 1800)(-3575 1900);
WIRE 16 -1 (-3825 1900)(-3575 1900);
WIRE 16 -1 (-3425 1800)(-3575 1800);
WIRE 16 -1 (-4025 4900)(-4850 4900);
FORCEPROP 0 LAST SIG_NAME CLK_100M_CPU1_RC_REFCLK1_R_DP
J 0
(-4800 4910);
DISPLAY 0.617021 (-4800 4910);
PAINT ORANGE (-4800 4910);
WIRE 16 -1 (-4025 4525)(-4850 4525);
FORCEPROP 0 LAST SIG_NAME CLK_100M_CPU1_RC_REFCLK1_R_DN
J 0
(-4800 4535);
DISPLAY 0.617021 (-4800 4535);
PAINT ORANGE (-4800 4535);
WIRE 16 -1 (-4025 4175)(-4850 4175);
FORCEPROP 2 LAST SIG_NAME CLK_100M_CPU1_RC_REFCLK0_R_DP
J 0
(-4810 4185);
DISPLAY 0.617021 (-4810 4185);
PAINT ORANGE (-4810 4185);
WIRE 16 -1 (-4025 3850)(-4850 3850);
FORCEPROP 2 LAST SIG_NAME CLK_100M_CPU1_RC_REFCLK0_R_DN
J 0
(-4810 3860);
DISPLAY 0.617021 (-4810 3860);
PAINT ORANGE (-4810 3860);
WIRE 16 -1 (-4025 3525)(-4850 3525);
FORCEPROP 2 LAST SIG_NAME CLK_100M_CPU1_PE_REFCLK_R_DP
J 0
(-4810 3535);
DISPLAY 0.617021 (-4810 3535);
PAINT ORANGE (-4810 3535);
WIRE 16 -1 (-4025 3200)(-4850 3200);
FORCEPROP 0 LAST SIG_NAME CLK_100M_CPU1_PE_REFCLK_R_DN
J 0
(-4810 3210);
DISPLAY 0.617021 (-4810 3210);
PAINT ORANGE (-4810 3210);
WIRE 16 -1 (-4025 2875)(-4850 2875);
FORCEPROP 0 LAST SIG_NAME CLK_100M_CPU1_BCLK2_R_DP
J 0
(-4800 2885);
DISPLAY 0.617021 (-4800 2885);
PAINT ORANGE (-4800 2885);
WIRE 16 -1 (-4025 2550)(-4850 2550);
FORCEPROP 2 LAST SIG_NAME CLK_100M_CPU1_BCLK2_R_DN
J 0
(-4800 2560);
DISPLAY 0.617021 (-4800 2560);
PAINT ORANGE (-4800 2560);
WIRE 16 -1 (-4025 2225)(-4850 2225);
FORCEPROP 2 LAST SIG_NAME CLK_100M_CPU1_BCLK1_R_DP
J 0
(-4800 2235);
DISPLAY 0.617021 (-4800 2235);
PAINT ORANGE (-4800 2235);
WIRE 16 -1 (-4025 1900)(-4850 1900);
FORCEPROP 2 LAST SIG_NAME CLK_100M_CPU1_BCLK1_R_DN
J 0
(-4800 1910);
DISPLAY 0.617021 (-4800 1910);
PAINT ORANGE (-4800 1910);
WIRE 16 -1 (-4025 1575)(-4850 1575);
FORCEPROP 2 LAST SIG_NAME CLK_100M_CPU1_BCLK0_R_DP
J 0
(-4800 1585);
DISPLAY 0.617021 (-4800 1585);
PAINT ORANGE (-4800 1585);
WIRE 16 -1 (-4025 1250)(-4850 1250);
FORCEPROP 2 LAST SIG_NAME CLK_100M_CPU1_BCLK0_R_DN
J 0
(-4800 1260);
DISPLAY 0.617021 (-4800 1260);
PAINT ORANGE (-4800 1260);
DOT 1 (775 4825);
DOT 1 (800 4500);
DOT 1 (775 4175);
DOT 1 (800 3850);
DOT 1 (800 3525);
DOT 1 (825 3200);
DOT 1 (800 2875);
DOT 1 (800 2550);
DOT 1 (800 2225);
DOT 1 (800 1900);
DOT 1 (800 1575);
DOT 1 (800 1250);
DOT 1 (-3550 4525);
DOT 1 (-3575 4900);
DOT 1 (-3575 4175);
DOT 1 (-3575 3200);
DOT 1 (-3575 3525);
DOT 1 (-3575 3850);
DOT 1 (-3575 2225);
DOT 1 (-3575 2550);
DOT 1 (-3575 2875);
DOT 1 (-3575 1250);
DOT 1 (-3575 1575);
DOT 1 (-3575 1900);
FORCENOTE
BOM_COST=SYS_CLOCK
(-5300 650) 0;
DISPLAY LEFT (-5300 650);
DISPLAY 1.021277 (-5300 650);
PAINT PURPLE (-5300 650);
FORCENOTE
ROOM=DB1200Z
(-5300 700) 0;
DISPLAY LEFT (-5300 700);
DISPLAY 1.021277 (-5300 700);
PAINT PURPLE (-5300 700);
QUIT
